G04 ================== begin FILE IDENTIFICATION RECORD ==================*
G04 Layout Name:  F:/<user>/2022/FB/R4006-TIMING/brd/gerber-3/R4006-B0001-02_R01.brd*
G04 Film Name:    R4006-B0001-02_R01_TSM*
G04 File Format:  Gerber RS274X*
G04 File Origin:  Cadence Allegro 17.2-S079*
G04 Origin Date:  Fri Feb 25 18:14:43 2022*
G04 *
G04 Layer:  PACKAGE GEOMETRY/SOLDERMASK_TOP*
G04 Layer:  BOARD GEOMETRY/SOLDERMASK_TOP*
G04 Layer:  BOARD GEOMETRY/OUTLINE*
G04 Layer:  PIN/SOLDERMASK_TOP*
G04 Layer:  VIA CLASS/SOLDERMASK_TOP*
G04 Layer:  MANUFACTURING/CELESTICA_LEGEND*
G04 *
G04 Offset:    (0.00 0.00)*
G04 Mirror:    No*
G04 Mode:      Positive*
G04 Rotation:  0*
G04 FullContactRelief:  No*
G04 UndefLineWidth:     40.00*
G04 ================== end FILE IDENTIFICATION RECORD ====================*
%FSLAX55Y55*MOIN*%
%IR0*IPPOS*OFA0.00000B0.00000*MIA0B0*SFA1.00000B1.00000*%
%ADD54R,.11X.012*%
%ADD100R,.012X.11*%
%ADD63R,.032X.13*%
%AMMACRO80*
4,1,6,.0125,.00252,
.0035,.00252,
.0035,-.0225,
-.0125,-.0225,
-.0125,.0225,
.0125,.0225,
.0125,.00252,
0.0*
%
%ADD80MACRO80*%
%AMMACRO45*
4,1,6,.00252,-.0125,
.00252,-.0035,
-.0225,-.0035,
-.0225,.0125,
.0225,.0125,
.0225,-.0125,
.00252,-.0125,
0.0*
%
%ADD45MACRO45*%
%AMMACRO79*
4,1,6,.0125,-.0225,
-.0125,-.0225,
-.0125,.0225,
.0035,.0225,
.0035,-.00252,
.0125,-.00252,
.0125,-.0225,
0.0*
%
%ADD79MACRO79*%
%ADD10C,.012*%
%ADD66R,.144X.054*%
%AMMACRO57*
4,1,6,-.0225,-.0125,
-.0225,.0125,
.0225,.0125,
.0225,-.0035,
-.00252,-.0035,
-.00252,-.0125,
-.0225,-.0125,
0.0*
%
%ADD57MACRO57*%
%ADD34R,.067X.122*%
%ADD27R,.054X.144*%
%ADD14C,.014*%
%ADD113C,.061*%
%ADD90R,.108X.049*%
%ADD56R,.032X.169*%
%ADD92R,.049X.108*%
%ADD17C,.09*%
%ADD16C,.028*%
%ADD75C,.0236*%
%ADD93R,.098X.134*%
%ADD48R,.024X.024*%
%ADD11C,.094*%
%ADD94R,.035X.035*%
%AMMACRO104*
4,1,8,.02819,.02481,
.02819,-.02481,
.01119,-.02481,
.01119,.01095,
-.01119,.01095,
-.01119,-.02481,
-.02819,-.02481,
-.02819,.02481,
.02819,.02481,
0.0*
%
%ADD104MACRO104*%
%ADD65R,.15X.1*%
%ADD59R,.1X.15*%
%ADD99R,.142X.12*%
%AMMACRO78*
4,1,6,-.0125,-.00252,
-.0035,-.00252,
-.0035,.0225,
.0125,.0225,
.0125,-.0225,
-.0125,-.0225,
-.0125,-.00252,
0.0*
%
%ADD78MACRO78*%
%AMMACRO58*
4,1,6,-.00252,.0125,
-.00252,.0035,
.0225,.0035,
.0225,-.0125,
-.0225,-.0125,
-.0225,.0125,
-.00252,.0125,
0.0*
%
%ADD58MACRO58*%
%ADD69R,.041X.012*%
%ADD68R,.031X.014*%
%ADD13R,.024X.022*%
%ADD42C,.11*%
%AMMACRO77*
4,1,6,-.0125,.0225,
.0125,.0225,
.0125,-.0225,
-.0035,-.0225,
-.0035,.00252,
-.0125,.00252,
-.0125,.0225,
0.0*
%
%ADD77MACRO77*%
%AMMACRO47*
4,1,6,.0225,.0125,
.0225,-.0125,
-.0225,-.0125,
-.0225,.0035,
.00252,.0035,
.00252,.0125,
.0225,.0125,
0.0*
%
%ADD47MACRO47*%
%ADD36C,.12*%
%ADD35R,.051X.024*%
%ADD84R,.05X.016*%
%ADD83R,.016X.05*%
%ADD81R,.021X.028*%
%ADD33R,.024X.051*%
%ADD22R,.016X.042*%
%ADD115R,.057X.02*%
%ADD109R,.064X.022*%
%ADD98R,.051X.016*%
%ADD88R,.037X.021*%
%ADD61R,.042X.017*%
%ADD40C,.104*%
%ADD18R,.043X.061*%
%ADD70R,.012X.057*%
%ADD67R,.014X.027*%
%ADD55R,.028X.014*%
%ADD50R,.02X.049*%
%ADD30R,.022X.064*%
%ADD20R,.028X.032*%
%ADD101R,.014X.028*%
%ADD96R,.049X.02*%
%ADD85R,.053X.016*%
%ADD82R,.016X.053*%
%ADD76R,.016X.045*%
%ADD51R,.028X.024*%
%ADD32R,.015X.018*%
%ADD31R,.018X.015*%
%ADD24R,.032X.028*%
%ADD107R,.092X.06*%
%ADD102R,.024X.028*%
%ADD73R,.019X.016*%
%ADD62R,.075X.014*%
%ADD53R,.016X.028*%
%ADD46R,.045X.016*%
%ADD29R,.043X.045*%
%ADD106C,.108*%
%ADD97R,.028X.016*%
%ADD86R,.037X.016*%
%ADD25R,.038X.034*%
%ADD23R,.016X.019*%
%ADD19R,.047X.061*%
%ADD15C,.135*%
%ADD91R,.092X.044*%
%ADD43R,.058X.042*%
%ADD37R,.034X.038*%
%AMMACRO112*
4,1,22,.0394,-.01575,
.03907,-.019515,
.038091,-.023166,
.036493,-.026591,
.034324,-.029687,
.031651,-.032359,
.028555,-.034527,
.025129,-.036124,
.021478,-.037101,
.01772,-.03743,
-.01772,-.03743,
-.021485,-.0371,
-.025136,-.036121,
-.028561,-.034523,
-.031657,-.032354,
-.034329,-.029681,
-.036497,-.026585,
-.038094,-.023159,
-.039071,-.019508,
-.0394,-.01575,
-.0394,.03743,
.0394,.03743,
.0394,-.01575,
0.0*
%
%ADD112MACRO112*%
%ADD111C,.128*%
%ADD72R,.076X.024*%
%ADD52R,.016X.049*%
%ADD49R,.042X.058*%
%ADD28R,.045X.091*%
%ADD110R,.096X.06*%
%ADD105R,.017X.048*%
%ADD95R,.049X.016*%
%ADD74R,.059X.043*%
%ADD64R,.066X.018*%
%ADD44R,.069X.024*%
%ADD41R,.059X.051*%
%ADD38R,.068X.016*%
%ADD26R,.018X.066*%
%ADD103R,.001X.001*%
%ADD89R,.043X.059*%
%ADD39R,.016X.068*%
%ADD12R,.039X.037*%
%ADD87R,.029X.039*%
%ADD60C,.248*%
%ADD71R,.059X.037*%
%ADD114R,.079X.063*%
%ADD108R,.108X.108*%
%ADD21O,.079X.039*%
%AMMACRO116*
4,1,22,.0394,-.03743,
-.0394,-.03743,
-.0394,.01575,
-.03907,.019515,
-.038091,.023166,
-.036493,.026591,
-.034324,.029687,
-.031651,.032359,
-.028555,.034527,
-.025129,.036124,
-.021478,.037101,
-.01772,.03743,
.01772,.03743,
.021485,.0371,
.025136,.036121,
.028561,.034523,
.031657,.032354,
.034329,.029681,
.036497,.026585,
.038094,.023159,
.039071,.019508,
.0394,.01575,
.0394,-.03743,
0.0*
%
%ADD116MACRO116*%
%ADD117C,.01*%
%ADD118C,.005*%
%ADD119C,.04*%
G75*
%LPD*%
G75*
G36*
G01X56043Y52807D02*
Y21660D01*
X55126Y20743D01*
X7138D01*
X3827D01*
X3033Y21537D01*
Y52807D01*
Y53530D01*
X34909D01*
X56043D01*
Y52807D01*
G37*
G36*
G01X50000Y433661D02*
Y353150D01*
X3937D01*
X3012D01*
Y391790D01*
Y433747D01*
X3854Y434589D01*
X50000D01*
Y433661D01*
G37*
G36*
G01X49557Y100950D02*
Y99050D01*
X53243D01*
Y100950D01*
X49557D01*
G37*
G36*
G01X51843Y156050D02*
Y157950D01*
X48157D01*
Y156050D01*
X51843D01*
G37*
G36*
G01X52443Y215650D02*
Y217550D01*
X48757D01*
Y215650D01*
X52443D01*
G37*
G36*
G01X48857Y268950D02*
Y267050D01*
X52543D01*
Y268950D01*
X48857D01*
G37*
G36*
G01X66900Y393840D02*
X70367D01*
G03X70820Y393323I933J360D01*
G01Y389600D01*
X66900D01*
Y393840D01*
G37*
G36*
G01X72233D02*
X75067D01*
G03X75540Y393312I933J360D01*
G01Y389600D01*
X71620D01*
Y393253D01*
G03X72233Y393840I-320J947D01*
G37*
G36*
G01X76933D02*
X79767D01*
G03X80260Y393302I933J360D01*
G01Y389600D01*
X76340D01*
Y393260D01*
G03X76933Y393840I-340J940D01*
G37*
G36*
G01X76947Y398880D02*
X79753D01*
G03X80260Y398302I947J320D01*
G01Y395098D01*
G03X79802Y394640I440J-898D01*
G01X76898D01*
G03X76340Y395140I-898J-440D01*
G01Y398260D01*
G03X76947Y398880I-340J940D01*
G37*
G36*
G01X72247D02*
X75053D01*
G03X75540Y398312I947J320D01*
G01Y395088D01*
G03X75102Y394640I460J-888D01*
G01X72198D01*
G03X71620Y395147I-898J-440D01*
G01Y398253D01*
G03X72247Y398880I-320J947D01*
G37*
G36*
G01X66900D02*
X70353D01*
G03X70820Y398323I947J320D01*
G01Y395077D01*
G03X70402Y394640I480J-877D01*
G01X66900D01*
Y398880D01*
G37*
G36*
G01X76960Y403920D02*
X79740D01*
G03X80260Y403302I960J280D01*
G01Y400098D01*
G03X79823Y399680I440J-898D01*
G01X76877D01*
G03X76340Y400140I-877J-480D01*
G01Y403260D01*
G03X76960Y403920I-340J940D01*
G37*
G36*
G01X72260D02*
X75040D01*
G03X75540Y403312I960J280D01*
G01Y400088D01*
G03X75123Y399680I460J-888D01*
G01X72177D01*
G03X71620Y400147I-877J-480D01*
G01Y403253D01*
G03X72260Y403920I-320J947D01*
G37*
G36*
G01X66900D02*
X70340D01*
G03X70820Y403323I960J280D01*
G01Y400077D01*
G03X70423Y399680I480J-877D01*
G01X66900D01*
Y403920D01*
G37*
G36*
G01X76971Y408960D02*
X79729D01*
G03X80260Y408302I971J240D01*
G01Y405098D01*
G03X79846Y404720I440J-898D01*
G01X76854D01*
G03X76340Y405140I-854J-520D01*
G01Y408260D01*
G03X76971Y408960I-340J941D01*
G37*
G36*
G01X66900D02*
X70329D01*
G03X70820Y408323I971J240D01*
G01Y405077D01*
G03X70446Y404720I480J-877D01*
G01X66900D01*
Y408960D01*
G37*
G36*
G01X72271D02*
X75029D01*
G03X75540Y408312I971J240D01*
G01Y405088D01*
G03X75146Y404720I460J-888D01*
G01X72154D01*
G03X71620Y405147I-854J-520D01*
G01Y408253D01*
G03X72271Y408960I-320J947D01*
G37*
G36*
G01X76340Y414000D02*
X80260D01*
Y410098D01*
G03X79872Y409760I441J-898D01*
G01X76828D01*
G03X76340Y410140I-828J-560D01*
G01Y414000D01*
G37*
G36*
G01X71620D02*
X75540D01*
Y410088D01*
G03X75172Y409760I461J-887D01*
G01X72128D01*
G03X71620Y410147I-828J-560D01*
G01Y414000D01*
G37*
G36*
G01X66900D02*
X70820D01*
Y410077D01*
G03X70472Y409760I480J-877D01*
G01X66900D01*
Y414000D01*
G37*
G36*
G01X81633Y393840D02*
X84467D01*
G03X84980Y393292I933J360D01*
G01Y389600D01*
X81060D01*
Y393267D01*
G03X81633Y393840I-360J933D01*
G37*
G36*
G01X86333D02*
X89700D01*
Y389600D01*
X85780D01*
Y393275D01*
G03X86333Y393840I-380J925D01*
G37*
G36*
G01X86347Y398880D02*
X89700D01*
Y394640D01*
X86298D01*
G03X85780Y395125I-898J-440D01*
G01Y398275D01*
G03X86347Y398880I-380J925D01*
G37*
G36*
G01X81647D02*
X84453D01*
G03X84980Y398292I948J319D01*
G01Y395108D01*
G03X84502Y394640I420J-907D01*
G01X81598D01*
G03X81060Y395133I-898J-440D01*
G01Y398267D01*
G03X81647Y398880I-360J933D01*
G37*
G36*
G01X86360Y403920D02*
X89700D01*
Y399680D01*
X86277D01*
G03X85780Y400125I-877J-480D01*
G01Y403275D01*
G03X86360Y403920I-380J925D01*
G37*
G36*
G01X81660D02*
X84440D01*
G03X84980Y403292I960J280D01*
G01Y400108D01*
G03X84523Y399680I421J-907D01*
G01X81577D01*
G03X81060Y400133I-877J-480D01*
G01Y403267D01*
G03X81660Y403920I-360J933D01*
G37*
G36*
G01X86371Y408960D02*
X89700D01*
Y404720D01*
X86254D01*
G03X85780Y405125I-854J-520D01*
G01Y408275D01*
G03X86371Y408960I-380J925D01*
G37*
G36*
G01X81671D02*
X84429D01*
G03X84980Y408292I971J240D01*
G01Y405108D01*
G03X84546Y404720I421J-907D01*
G01X81554D01*
G03X81060Y405133I-854J-520D01*
G01Y408267D01*
G03X81671Y408960I-360J933D01*
G37*
G36*
G01X85780Y414000D02*
X89700D01*
Y409760D01*
X86228D01*
G03X85780Y410125I-829J-560D01*
G01Y414000D01*
G37*
G36*
G01X81060D02*
X84980D01*
Y410108D01*
G03X84572Y409760I421J-907D01*
G01X81528D01*
G03X81060Y410133I-829J-560D01*
G01Y414000D01*
G37*
G36*
G01X182479Y287500D02*
X106000D01*
X102000Y283500D01*
Y84000D01*
X106000Y80000D01*
X174000D01*
X181000Y87000D01*
X225000D01*
X232000Y80000D01*
X305000D01*
X308500Y83500D01*
Y155000D01*
X305000Y158500D01*
X270500D01*
X268000Y161000D01*
Y163000D01*
Y207000D01*
X271500Y210500D01*
X306500D01*
X309000Y213000D01*
Y282500D01*
X304500Y287000D01*
X201000D01*
X182979D01*
X182479Y287500D01*
G37*
G36*
G01X165150Y301900D02*
Y304050D01*
G03X166150Y305050I1000J0D01*
G01X170850D01*
Y301900D01*
X165150D01*
G37*
G36*
G01Y301100D02*
X170850D01*
Y298980D01*
G03X169850Y299950I-1000J-30D01*
G03X168850Y298950I0J-1000D01*
G03X169770Y297953I1000J0D01*
G01Y297950D01*
X165150D01*
Y301100D01*
G37*
G36*
G01X177200Y22231D02*
Y1981D01*
X179200Y-19D01*
X310200D01*
X312200Y1981D01*
Y22231D01*
X177200D01*
G37*
G36*
G01X174343Y289050D02*
Y290950D01*
X170657D01*
Y289050D01*
X174343D01*
G37*
G36*
G01X390800Y291650D02*
X388650D01*
G03X387650Y292650I0J1000D01*
G01Y297350D01*
X390800D01*
Y291650D01*
G37*
G36*
G01X409720Y404950D02*
X411950D01*
Y402167D01*
G03X411433Y401650I400J-917D01*
G01X408650D01*
Y403940D01*
G03X409650Y402950I1000J10D01*
G03X410650Y403950I0J1000D01*
G03X409718Y404948I-1000J0D01*
G01X409720Y404950D01*
G37*
G36*
G01X408650Y396750D02*
X411433D01*
G03X411950Y396233I917J400D01*
G01Y393450D01*
X409680D01*
G03X410650Y394450I-30J1000D01*
G03X409650Y395450I-1000J0D01*
G03X408651Y394499I0J-1000D01*
G01X408650Y394500D01*
Y396750D01*
G37*
G36*
G01Y400850D02*
X411433D01*
G03X411950Y400333I917J400D01*
G01Y398067D01*
G03X411433Y397550I400J-917D01*
G01X408650D01*
Y400850D01*
G37*
G36*
G01X416850Y404950D02*
X419100D01*
Y404949D01*
G03X418150Y403950I50J-999D01*
G03X419150Y402950I1000J0D01*
G03X420147Y403870I0J1000D01*
G01X420150D01*
Y401650D01*
X417367D01*
G03X416850Y402167I-917J-400D01*
G01Y404950D01*
G37*
G36*
G01X417367Y396750D02*
X420150D01*
Y394480D01*
G03X419150Y395450I-1000J-30D01*
G03X418150Y394450I0J-1000D01*
G03X419140Y393450I1000J0D01*
G01X416850D01*
Y396233D01*
G03X417367Y396750I-400J917D01*
G37*
G36*
G01Y400850D02*
X420150D01*
Y397550D01*
X417367D01*
G03X416850Y398067I-917J-400D01*
G01Y400333D01*
G03X417367Y400850I-400J917D01*
G37*
G36*
G01X413267D02*
X415533D01*
G03X416050Y400333I917J400D01*
G01Y398067D01*
G03X415533Y397550I400J-917D01*
G01X413267D01*
G03X412750Y398067I-917J-400D01*
G01Y400333D01*
G03X413267Y400850I-400J917D01*
G37*
G36*
G01Y396750D02*
X415533D01*
G03X416050Y396233I917J400D01*
G01Y393450D01*
X412750D01*
Y396233D01*
G03X413267Y396750I-400J917D01*
G37*
G36*
G01X412750Y404950D02*
X416050D01*
Y402167D01*
G03X415533Y401650I400J-917D01*
G01X413267D01*
G03X412750Y402167I-917J-400D01*
G01Y404950D01*
G37*
G36*
G01X439150Y287200D02*
Y283800D01*
G03X438150Y282800I-1000J0D01*
G01X436000D01*
Y287200D01*
X439150D01*
G37*
G36*
G01X432050Y288000D02*
Y291400D01*
G03X433050Y292400I1000J0D01*
G01X435200D01*
Y288000D01*
X432050D01*
G37*
G36*
G01X513650Y270300D02*
Y268150D01*
G03X512650Y267150I-1000J0D01*
G01X507950D01*
Y270300D01*
X513650D01*
G37*
G36*
G01X509010Y274250D02*
X513650D01*
Y271100D01*
X507950D01*
Y273240D01*
G03X508950Y272250I1000J10D01*
G03X509950Y273250I0J1000D01*
G03X509010Y274248I-1000J0D01*
G01Y274250D01*
G37*
G36*
G01X559650Y68300D02*
Y70450D01*
G03X560650Y71450I1000J0D01*
G01X565350D01*
Y68300D01*
X559650D01*
G37*
G36*
G01Y67500D02*
X565350D01*
Y65370D01*
G03X564350Y66350I-1000J-20D01*
G03X563350Y65350I0J-1000D01*
G03X564310Y64351I1000J0D01*
G01Y64350D01*
X559650D01*
Y67500D01*
G37*
G36*
G01X556050Y373413D02*
X551150D01*
Y372413D01*
X556050D01*
Y373413D01*
G37*
G36*
G01Y369869D02*
X551150D01*
Y368869D01*
X556050D01*
Y369869D01*
G37*
G36*
G01Y380499D02*
X551150D01*
Y379499D01*
X556050D01*
Y380499D01*
G37*
G36*
G01Y376956D02*
X551150D01*
Y375956D01*
X556050D01*
Y376956D01*
G37*
G36*
G01X596490Y211350D02*
X598600D01*
Y207450D01*
X595450D01*
Y210330D01*
G03X596450Y209350I1000J20D01*
G03X597450Y210350I0J1000D01*
G03X596490Y211349I-1000J0D01*
G01Y211350D01*
G37*
G36*
G01X599400D02*
X602550D01*
Y208470D01*
G03X601550Y209450I-1000J-20D01*
G03X600550Y208450I0J-1000D01*
G03X601500Y207451I1000J0D01*
G01Y207450D01*
X599400D01*
Y211350D01*
G37*
G36*
G01X620500Y54134D02*
X620551D01*
Y90157D01*
X656988D01*
Y54059D01*
X656177Y53248D01*
X620500D01*
Y54134D01*
G37*
G36*
G01X620551Y392520D02*
X657019D01*
Y433813D01*
X656272Y434560D01*
X620551D01*
Y433661D01*
Y392520D01*
G37*
G36*
G01X41528Y36811D02*
G03I-12000J0D01*
G37*
G36*
G01Y373031D02*
G03I-12000J0D01*
G37*
G36*
G01X155767Y106043D02*
G03I-12200J0D01*
G37*
G36*
G01X158267Y268043D02*
G03I-12200J0D01*
G37*
G36*
G01X280767Y112143D02*
G03I-12200J0D01*
G37*
G36*
G01Y255943D02*
G03I-12200J0D01*
G37*
G36*
G01X652039Y65354D02*
G03I-12000J0D01*
G37*
G36*
G01Y417835D02*
G03I-12000J0D01*
G37*
G36*
G01X120657Y379950D02*
X124343D01*
Y378050D01*
X120657D01*
Y379950D01*
G37*
G36*
G01X126157D02*
X129843D01*
Y378050D01*
X126157D01*
Y379950D01*
G37*
G36*
G01X147943Y391050D02*
Y389150D01*
X144257D01*
Y391050D01*
X147943D01*
G37*
G36*
G01Y404050D02*
Y402150D01*
X144257D01*
Y404050D01*
X147943D01*
G37*
G36*
G01X147443Y409550D02*
Y407650D01*
X143757D01*
Y409550D01*
X147443D01*
G37*
G36*
G01X351957Y388250D02*
Y390150D01*
X355643D01*
Y388250D01*
X351957D01*
G37*
G36*
G01Y393750D02*
Y395650D01*
X355643D01*
Y393750D01*
X351957D01*
G37*
G36*
G01X351857Y411150D02*
Y413050D01*
X355543D01*
Y411150D01*
X351857D01*
G37*
G36*
G01X362723Y231757D02*
Y235443D01*
X364623D01*
Y231757D01*
X362723D01*
G37*
G36*
G01Y238357D02*
Y242043D01*
X364623D01*
Y238357D01*
X362723D01*
G37*
G36*
G01X393357Y278350D02*
X397043D01*
Y276450D01*
X393357D01*
Y278350D01*
G37*
G36*
G01X394750Y291650D02*
X391600D01*
Y297350D01*
X394750D01*
Y291650D01*
G37*
G36*
G01X397250Y310843D02*
X399150D01*
Y307157D01*
X397250D01*
Y310843D01*
G37*
G36*
G01X435200Y287200D02*
Y282800D01*
X432050D01*
Y287200D01*
X435200D01*
G37*
G36*
G01X439150Y292400D02*
Y288000D01*
X436000D01*
Y292400D01*
X439150D01*
G37*
G36*
G01X498143Y278650D02*
Y276750D01*
X494457D01*
Y278650D01*
X498143D01*
G37*
G36*
G01X529843Y271550D02*
X526157D01*
Y273450D01*
X529843D01*
Y271550D01*
G37*
G36*
G01X546843Y62550D02*
X543157D01*
Y64450D01*
X546843D01*
Y62550D01*
G37*
G36*
G01X550050Y232157D02*
Y235843D01*
X551950D01*
Y232157D01*
X550050D01*
G37*
G36*
G01X551443Y392150D02*
Y390250D01*
X547757D01*
Y392150D01*
X551443D01*
G37*
G36*
G01X563050Y232157D02*
Y235843D01*
X564950D01*
Y232157D01*
X563050D01*
G37*
G36*
G01X578843Y61850D02*
Y59950D01*
X575157D01*
Y61850D01*
X578843D01*
G37*
G36*
G01X568550Y232657D02*
Y236343D01*
X570450D01*
Y232657D01*
X568550D01*
G37*
G36*
G01X570257Y370250D02*
Y372150D01*
X573943D01*
Y370250D01*
X570257D01*
G37*
G54D100*
X558780Y213138D03*
X556220D03*
G54D110*
X614648Y127063D03*
Y137063D03*
Y147063D03*
Y157063D03*
Y167063D03*
Y177063D03*
G54D101*
X556516Y221996D03*
X560453D03*
X554547D03*
X558484D03*
G54D111*
X634055Y334449D03*
Y367519D03*
G54D102*
X562913Y221996D03*
X552087D03*
G54D103*
X555607Y363305D03*
G54D112*
X651582Y198425D03*
G54D10*
X8878Y21717D03*
X4878D03*
X4000Y25619D03*
Y29619D03*
Y33619D03*
Y37619D03*
Y41619D03*
Y45619D03*
Y49619D03*
Y281619D03*
Y285619D03*
Y289619D03*
Y293619D03*
Y297619D03*
Y301619D03*
Y305619D03*
Y309619D03*
Y313619D03*
Y337619D03*
Y341619D03*
Y345619D03*
Y349619D03*
Y353619D03*
Y357619D03*
Y361619D03*
Y365619D03*
Y369619D03*
Y373619D03*
Y377619D03*
Y381619D03*
Y385619D03*
Y389619D03*
Y393619D03*
Y397619D03*
Y401619D03*
Y405619D03*
Y409619D03*
Y413619D03*
Y417619D03*
Y421619D03*
Y425619D03*
Y429619D03*
X4413Y433598D03*
X8413D03*
X24878Y21717D03*
X20878D03*
X16878D03*
X12878D03*
X12413Y433598D03*
X16413D03*
X20413D03*
X24413D03*
X28413D03*
X44878Y21717D03*
X40878D03*
X36878D03*
X32878D03*
X28878D03*
X46000Y82000D03*
X32413Y433598D03*
X36413D03*
X40413D03*
X44413D03*
X55055Y25073D03*
X52878Y21717D03*
X48878D03*
X55055Y41073D03*
Y37073D03*
Y33073D03*
Y29073D03*
X61463Y54048D03*
X57859Y52313D03*
X55558Y49041D03*
X55055Y45073D03*
X51765Y96600D03*
X48413Y433598D03*
X52413D03*
X56413D03*
X60413D03*
X77460Y54197D03*
X73460D03*
X69460D03*
X65460D03*
X76100Y154400D03*
X75950Y164200D03*
X79500Y234500D03*
X79600Y248900D03*
X79248Y266100D03*
X77964Y260100D03*
X73600Y252500D03*
X75800Y274300D03*
X67000Y283100D03*
X72000Y271400D03*
X68600Y274000D03*
X75500Y282500D03*
X63800Y274000D03*
X76700Y357500D03*
X67100D03*
X73500D03*
X70300D03*
X70500Y419000D03*
X75580Y419004D03*
X68413Y433598D03*
X72413D03*
X76413D03*
X80413D03*
X64413D03*
X97460Y54197D03*
X93460D03*
X89460D03*
X85460D03*
X81460D03*
X88300Y163900D03*
X86800Y230000D03*
X82500Y230500D03*
X84600Y248900D03*
X89600D03*
X85600Y263700D03*
X82500Y273200D03*
X87100Y271300D03*
X85800Y287452D03*
X98000Y420000D03*
X90000Y420500D03*
X85500D03*
X84413Y433598D03*
X88413D03*
X92413D03*
X96413D03*
X113460Y54197D03*
X109460D03*
X105460D03*
X101460D03*
X112800Y66600D03*
X112880Y73020D03*
X113700Y382500D03*
X104100D03*
X110500D03*
X107300D03*
X104413Y433598D03*
X108413D03*
X112413D03*
X100413D03*
X132920Y51926D03*
X129450Y53917D03*
X125460Y54197D03*
X121460D03*
X117460D03*
X126000Y67000D03*
Y62000D03*
X131500Y290500D03*
X116413Y433598D03*
X120413D03*
X124413D03*
X128413D03*
X132413D03*
X135299Y24509D03*
X150163Y21717D03*
X146163D03*
X142163D03*
X138163D03*
X135299Y28509D03*
Y32509D03*
Y36509D03*
Y40509D03*
Y44509D03*
X134977Y48496D03*
X148500Y62500D03*
X139500D03*
X144000D03*
X138500Y75000D03*
X145900Y75200D03*
X142070Y77900D03*
X142000Y69535D03*
X136000Y290500D03*
X138250Y372250D03*
X148500Y376000D03*
X138500Y387500D03*
X140413Y433598D03*
X144413D03*
X148413D03*
X136413D03*
X158163Y21717D03*
X154163D03*
X158795Y25667D03*
Y41667D03*
Y37667D03*
Y33667D03*
Y29667D03*
X160736Y49309D03*
X159112Y45654D03*
X163543Y52159D03*
X151840Y79935D03*
X153500Y390500D03*
X163300Y382900D03*
X151100Y386300D03*
X167100Y405600D03*
X152100Y399300D03*
X151530Y406300D03*
X153150Y394590D03*
X160600Y417400D03*
X152200Y416300D03*
X152413Y433598D03*
X156413D03*
X160413D03*
X164413D03*
X183170Y56390D03*
X180341Y47225D03*
X178196Y50601D03*
X180620Y77890D03*
X180390Y70720D03*
X180910Y63390D03*
X168413Y433598D03*
X172413D03*
X176413D03*
X180413D03*
X184413D03*
X191535Y28900D03*
X201950Y29050D03*
X187598Y36900D03*
X189500Y33000D03*
X186000D03*
X187598Y28900D03*
X191535Y41200D03*
X198135Y36500D03*
X195000Y54550D03*
X203000Y75000D03*
X196497Y76502D03*
X200413Y433598D03*
X188413D03*
X192413D03*
X196413D03*
X210500Y30500D03*
X207880Y78740D03*
X214810Y78810D03*
X208300Y289500D03*
X217300D03*
X212800D03*
X218500Y301700D03*
X213500D03*
X208500D03*
X209660Y331500D03*
X204413Y433598D03*
X208413D03*
X212413D03*
X216413D03*
X220413D03*
X232700Y29100D03*
X221800Y289500D03*
X224500Y302000D03*
X222000Y330000D03*
X224413Y433598D03*
X228413D03*
X232413D03*
X236413D03*
X254527Y28900D03*
X244619D03*
X254527Y33900D03*
X243500Y48650D03*
X252700Y44000D03*
X250222Y76300D03*
X247022D03*
X240508D03*
Y66700D03*
X243822Y76300D03*
X253422D03*
X240508Y69900D03*
Y73100D03*
X240413Y433598D03*
X244413D03*
X248413D03*
X252413D03*
X264339Y35300D03*
Y38500D03*
Y32100D03*
X264304Y28900D03*
X272309D03*
X264339Y41700D03*
X263300Y52200D03*
X269907Y76300D03*
X266707D03*
X263507D03*
X256413Y433598D03*
X260413D03*
X264413D03*
X268413D03*
X272413D03*
X280087Y35300D03*
Y38500D03*
Y41700D03*
Y32100D03*
X280052Y28900D03*
X288057D03*
X285055Y76300D03*
X281855D03*
X288255D03*
X273107D03*
X278655D03*
X284500Y181100D03*
Y184300D03*
Y187500D03*
X283400Y198700D03*
X280200D03*
X277000D03*
X286600D03*
X284500Y190700D03*
X286151Y329500D03*
X289600Y330100D03*
X288413Y433598D03*
X284413D03*
X280413D03*
X276413D03*
X295835Y35300D03*
Y38500D03*
Y41700D03*
Y32100D03*
X295800Y28900D03*
X295835Y44900D03*
Y48100D03*
X298726Y43529D03*
Y49471D03*
X307300Y61300D03*
X297700Y335100D03*
X298700Y327000D03*
Y323500D03*
X293200Y329500D03*
X304413Y433598D03*
X300413D03*
X296413D03*
X292413D03*
X307708Y28900D03*
X321402Y54197D03*
X317402D03*
X314763Y85237D03*
X312500Y87500D03*
X310237Y89763D03*
X317025Y82975D03*
X319510Y190299D03*
X322710D03*
X324000Y236000D03*
X318000Y268500D03*
X324300Y254700D03*
X322200Y320500D03*
Y325000D03*
X310600Y330500D03*
Y335000D03*
X322200Y338500D03*
X324413Y433598D03*
X320413D03*
X316413D03*
X312413D03*
X308413D03*
X329402Y54197D03*
X325402D03*
X337402D03*
X341402D03*
X333402D03*
X338599Y108500D03*
X341799D03*
X337500Y113000D03*
Y122600D03*
Y116200D03*
Y119400D03*
X329110Y190299D03*
X325910D03*
X327500Y232000D03*
X332600Y246600D03*
X328500Y238645D03*
X327800Y246800D03*
X334350Y282000D03*
X336500Y295000D03*
X336525Y320500D03*
Y325500D03*
X341500Y338500D03*
Y328500D03*
Y333500D03*
X336525Y330500D03*
X340413Y433598D03*
X336413D03*
X332413D03*
X328413D03*
X345402Y54197D03*
X349402D03*
X353402D03*
X357402D03*
X349000Y82500D03*
X359300Y92000D03*
X348199Y108500D03*
X348264Y104707D03*
X357864D03*
X344999Y108500D03*
X351464Y104707D03*
X354664D03*
X352300Y175000D03*
X345301Y196299D03*
Y186699D03*
Y193099D03*
Y189899D03*
X358400Y182700D03*
X345930Y217000D03*
X342900Y246800D03*
X354850Y276100D03*
X354800Y285600D03*
Y289800D03*
X344000Y295000D03*
X355000Y332500D03*
Y328000D03*
X358250Y340050D03*
X356413Y433598D03*
X352413D03*
X348413D03*
X344413D03*
X369402Y54197D03*
X373402D03*
X377402D03*
X361402D03*
X365402D03*
X373500Y78000D03*
X368900Y92000D03*
X373500Y94000D03*
X365700Y92000D03*
X362500D03*
X365101Y191559D03*
Y188359D03*
Y194759D03*
Y185159D03*
X361124Y349876D03*
X375500Y350500D03*
X376413Y433598D03*
X372413D03*
X368413D03*
X364413D03*
X360413D03*
X381402Y54197D03*
X385402D03*
X389402D03*
X393402D03*
X379500Y72500D03*
X380500Y77400D03*
X380400Y81600D03*
X381700Y92400D03*
X390000Y100500D03*
X383128Y178372D03*
X391600Y304800D03*
X379300Y305000D03*
X383000Y328500D03*
Y333500D03*
Y346600D03*
X388500Y391000D03*
X393500D03*
X388500Y400000D03*
X393500D03*
X393000Y418500D03*
X392413Y433598D03*
X388413D03*
X384413D03*
X380413D03*
X397402Y54197D03*
X401402D03*
X405402D03*
X409402D03*
X396400Y100500D03*
X409200D03*
X398450Y116099D03*
X408050D03*
X401650D03*
X404850D03*
X405463Y383000D03*
X410463D03*
X398500Y391000D03*
Y400000D03*
X403000Y418500D03*
X398000D03*
X408413Y433598D03*
X404413D03*
X400413D03*
X396413D03*
X417402Y54197D03*
X421402D03*
X425402D03*
X429402D03*
X413402D03*
X413622Y75000D03*
X421360Y359970D03*
X415463Y383000D03*
X414000Y419000D03*
X422337Y424000D03*
X416800D03*
X428413Y433598D03*
X424413D03*
X420413D03*
X416413D03*
X412413D03*
X433402Y54197D03*
X437402D03*
X441402D03*
X445402D03*
X444050Y116599D03*
X434450D03*
X437650D03*
X440850D03*
X446500Y289500D03*
X441500Y297500D03*
X439500Y337892D03*
X442500Y336089D03*
X439500Y341500D03*
X443000Y386500D03*
Y401500D03*
Y396500D03*
X432000D03*
X444000Y406500D03*
X431900Y392200D03*
X431169Y401169D03*
X444000Y416500D03*
Y411500D03*
X444413Y433598D03*
X440413D03*
X436413D03*
X432413D03*
X449402Y54197D03*
X453402D03*
X457402D03*
X461402D03*
X450930Y122167D03*
X460530D03*
X457330D03*
X454130D03*
X464413Y433598D03*
X460413D03*
X456413D03*
X452413D03*
X448413D03*
X465402Y54197D03*
X469402D03*
X473402D03*
X477402D03*
X481402D03*
X470462Y369462D03*
X470500Y395000D03*
X480413Y433598D03*
X476413D03*
X472413D03*
X468413D03*
X485402Y54197D03*
X489402D03*
X493402D03*
X497402D03*
X490970Y133500D03*
Y138500D03*
X488500Y359000D03*
X493500D03*
X496413Y433598D03*
X492413D03*
X488413D03*
X484413D03*
X501402Y54197D03*
X505402D03*
X509402D03*
X513402D03*
X500500Y271100D03*
X500000Y278799D03*
X503000Y354600D03*
X516413Y433598D03*
X512413D03*
X508413D03*
X504413D03*
X500413D03*
X517402Y54197D03*
X521402D03*
X525402D03*
X529402D03*
X533402D03*
X533000Y95000D03*
Y99500D03*
X522400Y270700D03*
X522600Y276200D03*
X528500Y299000D03*
X532300Y425700D03*
X532413Y433598D03*
X528413D03*
X524413D03*
X520413D03*
X537402Y54197D03*
X541402D03*
X545402D03*
X549402D03*
X549500Y69400D03*
X548158Y228033D03*
X545250Y256300D03*
X539977Y275124D03*
X540318Y270436D03*
X537500Y296607D03*
X550643Y400900D03*
X548413Y433598D03*
X544413D03*
X540413D03*
X536413D03*
X553402Y54197D03*
X557402D03*
X561402D03*
X565402D03*
X568600Y76000D03*
X566600Y212900D03*
X553122Y227979D03*
X559500Y228000D03*
X566700Y227500D03*
X568000Y356700D03*
X552000Y367597D03*
Y371141D03*
X555200Y367597D03*
Y371141D03*
X555569Y388051D03*
X552000Y374684D03*
Y378227D03*
X555200D03*
Y374684D03*
X568413Y433598D03*
X564413D03*
X560413D03*
X556413D03*
X552413D03*
X569402Y54197D03*
X573402D03*
X577402D03*
X581402D03*
X585402D03*
X572500Y60301D03*
X572870Y67570D03*
X577100Y227900D03*
X581400Y262100D03*
Y272100D03*
Y282100D03*
X581500Y302100D03*
X576200Y342500D03*
X584413Y433598D03*
X580413D03*
X576413D03*
X572413D03*
X589402Y54197D03*
X593402D03*
X597402D03*
X601402D03*
X597000Y199900D03*
X591902Y200300D03*
X601902Y200100D03*
X594153Y220500D03*
X589953Y236600D03*
X591000Y261500D03*
X590500Y301500D03*
X600413Y433598D03*
X596413D03*
X592413D03*
X588413D03*
X605402Y54197D03*
X609402D03*
X613402D03*
X617402D03*
X621402D03*
X606902Y200400D03*
X619961Y230874D03*
Y221274D03*
Y224474D03*
Y227674D03*
X620413Y433598D03*
X616413D03*
X612413D03*
X608413D03*
X604413D03*
X625402Y54197D03*
X629402D03*
X633500Y205906D03*
X625800Y215874D03*
X633000Y267000D03*
X636413Y433598D03*
X632413D03*
X628413D03*
X624413D03*
X649402Y54197D03*
X653402D03*
X656039Y57205D03*
Y61205D03*
Y65205D03*
Y69205D03*
Y73205D03*
Y77205D03*
Y81205D03*
Y85205D03*
Y89205D03*
Y93205D03*
Y97205D03*
Y101205D03*
Y105205D03*
Y109205D03*
Y113205D03*
Y117205D03*
Y121205D03*
Y125205D03*
Y129205D03*
Y145205D03*
Y133205D03*
Y137205D03*
Y141205D03*
Y149205D03*
Y153205D03*
Y157205D03*
Y161205D03*
Y165205D03*
Y169205D03*
Y173205D03*
Y177205D03*
Y181205D03*
Y235585D03*
Y311909D03*
Y315909D03*
Y319909D03*
Y323909D03*
Y327909D03*
Y331909D03*
Y335909D03*
Y339909D03*
Y343909D03*
Y347909D03*
Y351909D03*
Y355909D03*
Y359909D03*
Y363909D03*
Y367909D03*
Y371909D03*
Y375909D03*
Y379909D03*
Y383909D03*
Y387909D03*
Y391909D03*
Y395909D03*
Y399909D03*
Y403909D03*
Y407909D03*
Y411909D03*
Y415909D03*
Y419909D03*
Y423909D03*
Y427909D03*
Y431909D03*
X652413Y433598D03*
X648413D03*
X644413D03*
X640413D03*
G54D20*
X28100Y156898D03*
Y152698D03*
X23600Y156898D03*
Y152698D03*
X19100Y156898D03*
Y152698D03*
X24200Y266408D03*
X19700D03*
X24200Y270608D03*
X19700D03*
X18000Y318900D03*
X23000D03*
X28000D03*
X18000Y323100D03*
X23000D03*
X28000D03*
X44300Y64700D03*
Y68900D03*
X45500Y108390D03*
Y112590D03*
Y117800D03*
Y122000D03*
X32600Y156898D03*
Y152698D03*
X37100Y156898D03*
Y152698D03*
X41600Y156898D03*
Y152698D03*
X45500Y164400D03*
Y178100D03*
Y173900D03*
Y168600D03*
X45200Y232600D03*
Y236800D03*
X37700Y266408D03*
X42200D03*
X33200D03*
X28700D03*
X37700Y270608D03*
X42200D03*
X33200D03*
X28700D03*
X43000Y318900D03*
X38000D03*
X33000D03*
X43000Y323100D03*
X38000D03*
X33000D03*
X58000Y88400D03*
Y92600D03*
X48500D03*
Y88400D03*
X53500D03*
Y92600D03*
X62500Y108400D03*
Y112600D03*
X50500Y112590D03*
Y108390D03*
X58000Y144400D03*
X48000D03*
X53000D03*
X60600Y164745D03*
X58000Y148600D03*
X48000D03*
X53000D03*
X60600Y168945D03*
X57500Y204900D03*
Y209100D03*
X48000D03*
Y204900D03*
X53000D03*
Y209100D03*
X51452Y227500D03*
Y223300D03*
X46452D03*
Y227500D03*
X57800Y256900D03*
Y261100D03*
X47800D03*
Y256900D03*
X53000Y258400D03*
Y262600D03*
X59500Y355400D03*
Y359600D03*
X71400Y225200D03*
Y229400D03*
X64000Y222900D03*
Y227100D03*
X71500Y244400D03*
Y240200D03*
X76948Y252500D03*
Y256700D03*
X80648Y283100D03*
Y278900D03*
X83500Y252400D03*
Y256600D03*
X107500Y293900D03*
Y298100D03*
X112500Y293900D03*
Y298100D03*
X102500D03*
Y293900D03*
X110500Y368900D03*
Y373100D03*
X115500Y368900D03*
Y373100D03*
X105500Y368900D03*
Y373100D03*
X117500Y293900D03*
Y298100D03*
X144500Y370400D03*
Y374600D03*
X138500Y408400D03*
Y412600D03*
X154800Y66320D03*
Y62120D03*
X153000Y300400D03*
X151000Y320600D03*
Y316400D03*
X153000Y304600D03*
X155600Y416200D03*
Y412000D03*
X183500Y293900D03*
Y298100D03*
X199770Y59000D03*
Y63200D03*
X188500Y298100D03*
Y293900D03*
X195900Y324700D03*
Y328900D03*
X210500Y59400D03*
X215000D03*
X204770Y59000D03*
X210500Y63600D03*
X215000D03*
X204770Y63200D03*
X217300Y297300D03*
Y293100D03*
X212800Y297300D03*
Y293100D03*
X208300Y297300D03*
Y293100D03*
X217600Y384500D03*
Y388700D03*
X221800Y297300D03*
Y293100D03*
X226280Y328700D03*
Y324500D03*
X251122Y58400D03*
Y62600D03*
X325900Y196900D03*
Y201100D03*
Y206400D03*
Y210600D03*
X338484Y251100D03*
X333500D03*
X328500D03*
X338484Y255300D03*
X333500D03*
X328500D03*
X325500Y370600D03*
Y366400D03*
X357500Y162100D03*
Y157900D03*
X355400Y178749D03*
Y174549D03*
X354600Y251300D03*
X343500Y251100D03*
X354600Y255500D03*
X343500Y255300D03*
X358200Y285600D03*
Y276100D03*
Y280300D03*
Y289800D03*
X344300Y381600D03*
Y385800D03*
X377000Y87400D03*
Y91600D03*
X360400Y174549D03*
Y178749D03*
X370500Y238400D03*
Y242600D03*
X376000D03*
Y238400D03*
X366200Y297600D03*
Y301800D03*
X362300Y387800D03*
Y383600D03*
X391900Y251000D03*
X386000D03*
X380100D03*
X391900Y255200D03*
X386000D03*
X380100D03*
X379700Y284900D03*
Y296900D03*
Y301100D03*
Y289100D03*
X387000Y346600D03*
Y342400D03*
X401000Y107100D03*
Y102900D03*
X405500Y107100D03*
Y102900D03*
X403700Y251000D03*
X397800D03*
X409300D03*
X403700Y255200D03*
X397800D03*
X409300D03*
X408000Y347100D03*
Y342900D03*
X420500Y87900D03*
Y92100D03*
X420900Y251000D03*
X415000D03*
X420900Y255200D03*
X415000D03*
X436900Y107300D03*
Y103100D03*
X441400Y107300D03*
Y103100D03*
X439500Y241900D03*
Y246100D03*
X444000D03*
Y241900D03*
X439000Y269900D03*
Y274100D03*
X434000Y345400D03*
Y349600D03*
X458500Y113900D03*
Y118100D03*
X453000Y113900D03*
Y118100D03*
X453500Y232400D03*
X457500Y246100D03*
Y241900D03*
X448500Y246100D03*
Y241900D03*
X453500Y236600D03*
X453000Y246100D03*
Y241900D03*
X462000Y246100D03*
Y241900D03*
X453000Y389100D03*
Y384900D03*
X465000Y234100D03*
Y229900D03*
X473500Y350400D03*
Y354600D03*
X478500Y350400D03*
Y354600D03*
X496100Y268600D03*
X496000Y263600D03*
Y259400D03*
X488900Y268600D03*
X496100Y272800D03*
X488900D03*
X488500Y354600D03*
Y350400D03*
X483500D03*
Y354600D03*
X498500D03*
Y350400D03*
X493500Y354600D03*
Y350400D03*
X533100Y223800D03*
Y228000D03*
X527800Y265300D03*
Y261100D03*
X532800Y265300D03*
Y261100D03*
X527000Y276900D03*
Y281100D03*
X531500D03*
Y276900D03*
X541000Y179400D03*
Y183600D03*
X545000Y208900D03*
Y213100D03*
X546500Y232400D03*
Y236600D03*
X564000Y94400D03*
Y98600D03*
X555500Y232400D03*
X560000D03*
X555500Y236600D03*
X560000D03*
X577200Y65800D03*
Y70000D03*
X577500Y75400D03*
Y79600D03*
X570000Y210900D03*
Y215100D03*
X575400Y232400D03*
Y236600D03*
X591902Y195065D03*
Y190865D03*
X596902Y195065D03*
Y190865D03*
X601902D03*
Y195065D03*
X606902D03*
Y190865D03*
X614100Y227800D03*
Y232000D03*
X628900Y197074D03*
Y201274D03*
G54D104*
X553600Y364025D03*
G54D11*
X6039Y61260D03*
Y81260D03*
Y118346D03*
Y138346D03*
Y175433D03*
Y195433D03*
Y232520D03*
Y252520D03*
X26039Y61260D03*
Y81260D03*
Y118346D03*
Y138346D03*
Y175433D03*
Y195433D03*
Y232520D03*
Y252520D03*
G54D113*
X640952Y201181D03*
Y220867D03*
G54D21*
X24807Y335985D03*
Y347245D03*
X43705Y331655D03*
Y351576D03*
G54D114*
X651582Y214961D03*
Y207087D03*
G54D12*
X6874Y91633D03*
Y102067D03*
Y159154D03*
Y148720D03*
Y216241D03*
Y205807D03*
Y262893D03*
Y273327D03*
Y319980D03*
Y330414D03*
G54D105*
X551631Y383456D03*
X555569D03*
G54D30*
X78260Y224650D03*
Y242750D03*
X85940Y224650D03*
X83380D03*
X80820D03*
X83380Y242750D03*
X80820D03*
X85940D03*
X209660Y308450D03*
X212220D03*
X214780D03*
X217340D03*
X209660Y326550D03*
X212220D03*
X214780D03*
X217340D03*
G54D106*
X588779Y334449D03*
Y350984D03*
Y367519D03*
X605315Y334449D03*
Y350984D03*
G54D31*
X75897Y266100D03*
Y264131D03*
Y268069D03*
X81999D03*
Y266100D03*
Y264131D03*
G54D40*
X126067Y104043D03*
Y184043D03*
Y264043D03*
X253967Y93443D03*
X265967D03*
X277867D03*
X286067Y104043D03*
Y264043D03*
G54D115*
X641050Y216142D03*
Y213583D03*
Y211024D03*
Y208465D03*
Y205906D03*
G54D22*
X57676Y64606D03*
X51772Y77914D03*
X53740D03*
X55708Y64606D03*
X51772D03*
X53740D03*
X57676Y77914D03*
X55708D03*
X57676Y121692D03*
X55708D03*
X51772D03*
X53740D03*
X51772Y135000D03*
X53740D03*
X57676D03*
X55708D03*
X57676Y178779D03*
X55708D03*
X51772D03*
X53740D03*
X51772Y192087D03*
X53740D03*
X57676D03*
X55708D03*
X57676Y235866D03*
X51772Y249174D03*
X53740D03*
X55708Y235866D03*
X51772D03*
X53740D03*
X57676Y249174D03*
X55708D03*
G54D13*
X8252Y98523D03*
Y95177D03*
Y155610D03*
Y152264D03*
Y212697D03*
Y209351D03*
Y266437D03*
Y269783D03*
Y326870D03*
Y323524D03*
G54D116*
X651582Y223623D03*
G54D41*
X129831Y385154D03*
X121169D03*
Y391846D03*
X129831D03*
G54D23*
X52443Y100000D03*
X50357D03*
X48957Y157000D03*
X51043D03*
X49557Y216600D03*
X51643D03*
X51743Y268000D03*
X49657D03*
X123543Y379000D03*
X121457D03*
X126957D03*
X129043D03*
X147143Y390100D03*
X145057D03*
Y403100D03*
X147143D03*
X146643Y408600D03*
X144557D03*
X171457Y290000D03*
X173543D03*
X352757Y389200D03*
X354843D03*
Y394700D03*
X352757D03*
X352657Y412100D03*
X354743D03*
X394157Y277400D03*
X396243D03*
X495257Y277700D03*
X497343D03*
X529043Y272500D03*
X526957D03*
X543957Y63500D03*
X546043D03*
X548557Y391200D03*
X550643D03*
X578043Y60900D03*
X575957D03*
X571057Y371200D03*
X573143D03*
G54D107*
X599450Y127063D03*
Y137063D03*
Y147063D03*
Y157063D03*
Y167063D03*
Y177063D03*
G54D32*
X79932Y263049D03*
X77964D03*
Y269151D03*
X79932D03*
G54D50*
X163222Y391187D03*
Y402013D03*
X336678Y395787D03*
Y406613D03*
G54D14*
X11264Y152264D03*
X9000Y279000D03*
Y286000D03*
X17500Y91000D03*
X12500D03*
Y96000D03*
Y101000D03*
Y106000D03*
X19100Y148798D03*
X23600D03*
X28100D03*
X13620Y148720D03*
X13000Y157000D03*
X12500Y162000D03*
X17000Y204500D03*
X12500Y209500D03*
Y204500D03*
Y214500D03*
Y219500D03*
X11963Y266437D03*
X19000Y262500D03*
X24200Y262508D03*
X28700D03*
X12500Y261500D03*
X19900Y283000D03*
X15000Y279000D03*
X28700Y274300D03*
X13000Y273327D03*
X16000Y302500D03*
X28500Y302000D03*
X28000Y296500D03*
X16000Y297500D03*
Y307500D03*
X24100Y310900D03*
X18000Y314500D03*
X13000Y318700D03*
X11976Y323524D03*
X28000Y327000D03*
X44500Y73500D03*
X45500Y104390D03*
Y126000D03*
X41500Y127500D03*
X41409Y132591D03*
X45500Y161000D03*
X41600Y148798D03*
X32600Y148700D03*
X37100Y148798D03*
X45500Y182500D03*
X45000Y213000D03*
X46000Y219500D03*
X42000Y236800D03*
X40500Y262000D03*
X33200Y262508D03*
X43000Y255500D03*
X37400Y282900D03*
X29000Y291500D03*
X43000Y314500D03*
X33000D03*
X44500Y309000D03*
X39500D03*
X34500D03*
X35500Y327000D03*
X59600Y60200D03*
X55500Y59000D03*
X50500Y60228D03*
X51772Y73600D03*
X47600Y68900D03*
X60100Y73000D03*
X57000Y83500D03*
X51500D03*
X47000Y100000D03*
X61400Y104900D03*
X50500Y104800D03*
X59000Y96500D03*
X62500Y100500D03*
X57500Y101500D03*
X62500Y117000D03*
X48390Y128312D03*
X53740Y126000D03*
X51772Y130500D03*
X55922Y140543D03*
X46500Y133000D03*
X47500Y140500D03*
X53900Y157000D03*
X60600Y161200D03*
X60500Y152000D03*
X51400Y161600D03*
X54130Y152500D03*
X60600Y157000D03*
X48957Y153619D03*
X51772Y187987D03*
X53500Y183500D03*
X58000Y213500D03*
X54000D03*
X48000Y200500D03*
X53000D03*
X63000Y206000D03*
Y210500D03*
Y215000D03*
X49600Y213455D03*
X57500Y218500D03*
X51452Y219900D03*
X51772Y245074D03*
X53200Y240187D03*
X54590Y266870D03*
X48232Y264530D03*
X48500Y252500D03*
X55200Y253500D03*
X48500Y271500D03*
X52500Y278000D03*
X52800Y272000D03*
X57500Y289000D03*
X62000Y307000D03*
X61489Y332329D03*
X62000Y323500D03*
X55000Y336000D03*
Y355400D03*
X63500Y359600D03*
X62500Y365000D03*
Y369000D03*
Y373000D03*
Y378000D03*
Y382000D03*
X60300Y407100D03*
Y401100D03*
Y395100D03*
Y413100D03*
X67700Y65000D03*
X66400Y77400D03*
X71500Y77000D03*
X66000Y91100D03*
X76400Y87200D03*
X76321Y78300D03*
X78500Y82250D03*
X69500Y100000D03*
X73500Y112500D03*
X67000Y109000D03*
X79000Y100500D03*
X74000D03*
X67500Y114500D03*
X68000Y119000D03*
X73500D03*
X69500Y130000D03*
X74000D03*
X75000Y141700D03*
X64445Y168945D03*
X69000Y187500D03*
Y193000D03*
X69023Y198524D03*
X74593Y202207D03*
X71400Y221700D03*
X67500Y222900D03*
X67400Y227100D03*
X71400Y232900D03*
X71500Y247800D03*
X68000Y235500D03*
X67700Y240200D03*
X72400Y264600D03*
X80148Y253648D03*
X69500Y257800D03*
X64248Y258000D03*
X64500Y296750D03*
X78000Y291500D03*
X66000Y318500D03*
X79000Y315500D03*
X72000Y335000D03*
X66000Y323500D03*
X78635Y324492D03*
X79500Y341790D03*
Y348500D03*
X72000Y346300D03*
X73000Y365000D03*
X69500D03*
X66000D03*
X66500Y382000D03*
X70500D03*
X80700Y399200D03*
Y404200D03*
X71300D03*
Y399200D03*
X76000D03*
Y404200D03*
X71300Y394200D03*
X76000D03*
X80700D03*
X64300Y407600D03*
Y401600D03*
Y395600D03*
X66000Y419000D03*
X80500Y420500D03*
X80700Y409200D03*
X76000D03*
X71300D03*
X64300Y413600D03*
X88900Y67000D03*
X86000Y63100D03*
X84200Y75000D03*
X83300Y87100D03*
X82100Y79300D03*
X96500Y98000D03*
X92250Y97750D03*
X94500Y105000D03*
X89000Y110500D03*
X93500D03*
X90500Y105000D03*
X84000Y100500D03*
X87000Y130000D03*
Y120000D03*
X93500Y125000D03*
X87000Y125500D03*
X93500Y130000D03*
X86600Y141300D03*
X90500Y144500D03*
X95500Y145500D03*
X96500Y140000D03*
X91500D03*
X88400Y154900D03*
X93900Y155200D03*
X95200Y151000D03*
X88500Y149000D03*
X94500Y163000D03*
X98500Y159000D03*
X91000Y181500D03*
X88250Y177250D03*
X83500Y178000D03*
X97500Y172000D03*
X98500Y165500D03*
X92000Y173000D03*
X83500D03*
X95500Y192000D03*
X83500Y193000D03*
Y188500D03*
X90500D03*
X94500Y197000D03*
X90500Y193500D03*
X85750Y202750D03*
X97500Y214000D03*
X84500Y218000D03*
X95700Y227500D03*
X98500Y218500D03*
X93032Y246477D03*
X96000Y241000D03*
X85700Y236500D03*
X96500Y235500D03*
X87200Y258300D03*
X98700Y268300D03*
X98500Y256661D03*
X83200Y260300D03*
X86900Y267200D03*
X95900Y278900D03*
X94500Y312500D03*
X95000Y321500D03*
X95593Y333347D03*
X82500Y339000D03*
X82951Y327940D03*
X97500Y341000D03*
X95100Y351900D03*
X83000Y352500D03*
Y344500D03*
X95000D03*
X82800Y364600D03*
X94500Y373000D03*
Y369000D03*
Y364500D03*
X90500D03*
X86500D03*
X91500Y359500D03*
X83500Y360000D03*
X82800Y384600D03*
X94500Y380500D03*
X94000Y384500D03*
X90500D03*
X86500D03*
X94500Y376500D03*
X85400Y404200D03*
Y399200D03*
Y394200D03*
X96800Y408100D03*
X92800D03*
Y402100D03*
X96800D03*
Y396100D03*
X92800D03*
X94000Y420000D03*
X83000Y417000D03*
X85400Y409200D03*
X96800Y414100D03*
X92800D03*
X111330Y59810D03*
X103800Y76240D03*
X99000Y175500D03*
Y188500D03*
Y197500D03*
Y206500D03*
Y201500D03*
Y260025D03*
X98800Y272400D03*
X112500Y302000D03*
X107500D03*
X112500Y290000D03*
X102500D03*
Y302000D03*
X104500Y305500D03*
X105410Y318500D03*
X115253Y306247D03*
X99000Y350000D03*
X101500Y341000D03*
X104019Y347425D03*
X103000Y351500D03*
X113000Y344500D03*
X114000Y352000D03*
X103000Y364000D03*
X106500D03*
X110000D03*
X115500Y389000D03*
X104500Y377000D03*
X102500Y420000D03*
X119500Y57694D03*
X125000Y76500D03*
X126000Y72000D03*
X127500Y290500D03*
X117500Y290000D03*
X125095Y306095D03*
X129000Y321500D03*
X126000Y318000D03*
X129500Y328000D03*
X123500Y347500D03*
X130000Y349664D03*
X119000Y352000D03*
X124500D03*
X120000Y364500D03*
X129000Y365000D03*
Y370500D03*
X120000Y368000D03*
Y371500D03*
X132000Y379000D03*
X118500D03*
X132000Y375500D03*
X127000Y397061D03*
X117000Y397000D03*
X121169Y396892D03*
X150860Y67400D03*
X145000Y296500D03*
X141000Y298500D03*
X140100Y306900D03*
X135000Y312000D03*
X149500Y311034D03*
X140700Y320000D03*
X142130Y325630D03*
X146000Y334000D03*
X141916Y333916D03*
X140900Y355400D03*
X142000Y350000D03*
X148000Y370000D03*
X137000Y364000D03*
X145000Y359000D03*
X140123Y391604D03*
X135500Y383000D03*
Y390500D03*
X141000Y379500D03*
X148500Y380000D03*
X145000Y378000D03*
X140100Y395600D03*
X135500Y396000D03*
X135200Y408400D03*
X140000Y401000D03*
X135100Y412600D03*
X143500Y418000D03*
X153270Y58400D03*
X151200Y75191D03*
X160500Y75500D03*
Y71500D03*
X165000Y294000D03*
X166150Y304050D03*
X156800Y301100D03*
X156600Y295000D03*
X156000Y320500D03*
Y316500D03*
X166700Y338800D03*
X151000Y324200D03*
X156000Y325000D03*
Y329000D03*
X159100Y350400D03*
Y354600D03*
X166700Y343800D03*
X151500Y370000D03*
Y358000D03*
X159100Y382600D03*
X163600Y378600D03*
X157900Y387400D03*
X158500Y405200D03*
X160582Y410000D03*
X160550Y413400D03*
X151700Y411300D03*
X173170Y70840D03*
X168500Y294000D03*
X169850Y298950D03*
X182600Y289500D03*
X179500Y294600D03*
X176500Y290000D03*
X178000Y309500D03*
X173800Y324100D03*
X178600Y378600D03*
Y374600D03*
X175100Y382600D03*
Y387100D03*
X174600Y401600D03*
Y406100D03*
X175000Y394500D03*
X177000Y398000D03*
X174600Y410600D03*
X176000Y416000D03*
X188900Y54960D03*
X192160Y77840D03*
X190000Y301500D03*
Y305500D03*
X189500Y319000D03*
X189000Y326000D03*
X195900Y332500D03*
X191500Y413000D03*
X213500Y54000D03*
X208160Y73990D03*
X215000Y69000D03*
X220000D03*
X204770Y67780D03*
X207800Y83010D03*
X219200Y338800D03*
X205000Y348800D03*
Y353800D03*
X215000Y343800D03*
X219000Y348800D03*
X218000Y381100D03*
X219000Y392500D03*
X215500D03*
X216500Y396000D03*
X220000D03*
X217600Y415100D03*
X223500Y58250D03*
X231000Y68000D03*
Y71500D03*
X228500Y75500D03*
Y79000D03*
X226500Y334000D03*
X222500Y324500D03*
X238000Y345000D03*
X225500Y347500D03*
X230000D03*
X228500Y382500D03*
X221500Y378500D03*
X226000D03*
X221500Y415000D03*
X225600Y415100D03*
X229500Y415000D03*
X254000Y213500D03*
X241441Y215000D03*
X241900Y238800D03*
X249000Y290300D03*
X255400Y290100D03*
X247000Y344500D03*
X251000D03*
X255000D03*
X272330Y54871D03*
X259500Y54700D03*
Y70100D03*
X271000Y184500D03*
X269000Y215000D03*
X259000Y223000D03*
Y344500D03*
X282200Y179121D03*
X275260Y223000D03*
X280500Y224300D03*
X288000Y293000D03*
X288500Y317000D03*
X303500Y69400D03*
X296400Y70200D03*
X307500Y160500D03*
X303500Y164000D03*
X298284Y175184D03*
X298500Y184500D03*
X300995Y187611D03*
X297772Y188694D03*
X292000Y294720D03*
X299500Y295500D03*
X301000Y312000D03*
X297000Y310500D03*
X301000Y317000D03*
X293700Y317300D03*
X309000Y164500D03*
X312500Y160500D03*
X320500Y170000D03*
X311000Y193500D03*
X312000Y217000D03*
X308967Y204000D03*
X324000Y227500D03*
X312000Y234400D03*
X324000Y220750D03*
X312500Y225400D03*
X311900Y229900D03*
Y243400D03*
X311600Y252400D03*
X312000Y269000D03*
Y256500D03*
Y264500D03*
X314500Y276500D03*
X312000Y295500D03*
X317500D03*
X321000D03*
X324500D03*
X310500Y321000D03*
X312500Y307500D03*
X310600Y326000D03*
X321899Y343000D03*
X325000Y363000D03*
X320000Y398500D03*
X323000Y401500D03*
X321300Y423600D03*
X324800Y415200D03*
X321300Y416700D03*
X324800Y410700D03*
X336000Y61060D03*
X340500Y63500D03*
Y87000D03*
X338000Y102500D03*
X332550Y213550D03*
X341500Y233500D03*
X327923Y221577D03*
X335153Y217875D03*
X340953Y237000D03*
X328500Y258900D03*
X333500D03*
X338500Y259000D03*
X339500Y282000D03*
X330500Y291500D03*
X341000Y304000D03*
X332500Y306500D03*
X328000D03*
X338000Y315000D03*
X341400Y323500D03*
X326000Y374000D03*
X340500Y361300D03*
X332500D03*
X336500D03*
X325300Y387200D03*
X331500Y376000D03*
X338500D03*
X342000D03*
X339200Y380300D03*
X339300Y384000D03*
Y387700D03*
X340500Y391600D03*
X325300Y396200D03*
Y391700D03*
X336300Y423200D03*
Y415200D03*
Y419200D03*
X340800Y415200D03*
X349500Y61000D03*
X354500Y60920D03*
X345500Y87000D03*
X354000Y82500D03*
X344000Y103000D03*
X354000Y128000D03*
X351000Y130500D03*
X353500D03*
X356000D03*
X347500Y141500D03*
X350000D03*
X352500D03*
X355000D03*
X357000Y154200D03*
X353482Y154157D03*
X350085Y154300D03*
X350100Y169400D03*
X352600D03*
X357600D03*
X355100D03*
X347300Y179000D03*
X346500Y174000D03*
X344500Y181500D03*
X351200Y196600D03*
X349128Y186628D03*
X344000Y212000D03*
X350500Y229500D03*
X355500Y218000D03*
Y220500D03*
Y225500D03*
Y223000D03*
X351000Y233243D03*
X355000Y242500D03*
X354975Y247900D03*
X351000Y237000D03*
X343500Y258900D03*
X352500Y260000D03*
X348500D03*
X357680Y271780D03*
X357000Y295500D03*
X356000Y302300D03*
X349000Y303000D03*
Y295500D03*
X355500Y306500D03*
X346000D03*
X351000Y308000D03*
X355000Y337000D03*
X348418Y361300D03*
X344500D03*
X347700Y381600D03*
X347000Y391200D03*
X360000Y402400D03*
X359800Y397700D03*
X347600Y398800D03*
X348279Y405678D03*
X353000Y416500D03*
X350000Y419500D03*
X349500Y415000D03*
X346000Y416000D03*
X343700Y409900D03*
X348863Y410500D03*
X376838Y100230D03*
X369310Y109500D03*
X369172Y102828D03*
X367000Y126000D03*
X374300Y129000D03*
X371800D03*
X362000Y123500D03*
Y128000D03*
X374300Y132000D03*
X371800D03*
X376500Y141000D03*
X374000D03*
X360500Y154500D03*
X374900Y154228D03*
X371400Y154300D03*
X367900Y154228D03*
X363600Y176600D03*
X367600Y169300D03*
X364700Y169400D03*
X367400Y174400D03*
X373649Y185735D03*
X369560Y213000D03*
X372060D03*
X367000D03*
X364500D03*
X367000Y232000D03*
X372500D03*
X377500Y218500D03*
Y221000D03*
Y226500D03*
Y223500D03*
X360500Y243000D03*
X367000Y241243D03*
X373500Y247000D03*
X365500Y246500D03*
X369500Y267500D03*
X375800Y255200D03*
X376500Y269000D03*
X365000Y268000D03*
X362300Y286100D03*
X365800D03*
X370000Y276000D03*
X374500D03*
X374800Y291100D03*
X370300D03*
X361500Y296100D03*
X365800Y291100D03*
X362100Y291000D03*
X361400Y301500D03*
Y305800D03*
Y309900D03*
X365500Y305900D03*
X375500Y309200D03*
X371000Y326000D03*
X370000Y337000D03*
Y332500D03*
X366000Y350850D03*
X360700Y406200D03*
X363100Y418300D03*
X360311Y409880D03*
X363100Y422800D03*
X364500Y413500D03*
X382286Y86214D03*
X384000Y102980D03*
Y109500D03*
X379000Y141000D03*
X382000Y142000D03*
X378400Y154300D03*
X379800Y177100D03*
X380000Y204500D03*
X384091Y200091D03*
X379500Y237500D03*
X391900Y246800D03*
X386000D03*
X380100D03*
X386000Y259250D03*
X378000Y273500D03*
X389400Y281100D03*
X378000Y281000D03*
X382200D03*
X394800Y281300D03*
X388650Y292650D03*
X378000Y293200D03*
X383000D03*
X393300Y312500D03*
X383000Y323500D03*
X390000Y338500D03*
X392500Y329100D03*
Y323900D03*
X383000Y341500D03*
X384300Y368700D03*
X383900Y372600D03*
X381000Y365000D03*
X386500D03*
X389500Y370000D03*
X395000D03*
Y360000D03*
X383900Y384600D03*
X379500Y381000D03*
Y375800D03*
Y417500D03*
X407000Y120000D03*
X399500D03*
X399000Y221407D03*
Y225000D03*
X407500D03*
X397800Y246800D03*
X403700D03*
X409300D03*
X397800Y259300D03*
X403700D03*
X400000Y265500D03*
X399800Y278400D03*
X409100Y281300D03*
X409300Y286300D03*
X402000Y303000D03*
X409200Y291700D03*
X396981Y304482D03*
X407500Y300500D03*
X402500Y308000D03*
X397500Y312900D03*
X407500Y305000D03*
X397300Y320700D03*
X408500Y316500D03*
Y321998D03*
Y311000D03*
X398000Y336500D03*
X410000Y338000D03*
X398000Y352000D03*
X406610Y353410D03*
X411840Y353620D03*
X410000Y358543D03*
X409000Y371339D03*
X409650Y403950D03*
X412350Y401250D03*
Y397150D03*
X409650Y394450D03*
X422000Y77500D03*
X423000Y72950D03*
X417500Y75000D03*
X413500Y88500D03*
X425000Y87700D03*
X423000Y100500D03*
X427800Y100300D03*
X429400Y107500D03*
X420900Y246800D03*
X415000D03*
X420900Y259000D03*
X424900Y284300D03*
X423900Y278500D03*
X424900Y292900D03*
X413000Y300500D03*
X429442Y310075D03*
X417500Y337000D03*
Y352000D03*
X422500Y354500D03*
X428500Y346000D03*
X413500Y373500D03*
X419000D03*
X420500Y366000D03*
X425000Y381000D03*
X420500D03*
X419150Y394450D03*
X416450Y401250D03*
Y397150D03*
X419150Y403950D03*
X423500Y415500D03*
X434500Y77000D03*
X441400Y78100D03*
X433500Y100500D03*
X444200D03*
X431000Y116500D03*
X444000Y226000D03*
X436500Y233000D03*
X443500Y231500D03*
X444000Y250000D03*
X436500Y237500D03*
X439500Y250000D03*
X435000Y250500D03*
X443500Y236500D03*
X439500Y266500D03*
X444000Y263000D03*
X440000Y278500D03*
X434600Y278300D03*
X435500Y274500D03*
X445600Y278300D03*
X438150Y283800D03*
X447000Y283000D03*
X433050Y291400D03*
X446000Y294000D03*
X439000Y302000D03*
X434500D03*
X433000Y314320D03*
X435143Y306643D03*
X447000Y321998D03*
X440000Y332500D03*
X434000Y328000D03*
X447200Y347500D03*
X433000Y353500D03*
X433500Y366500D03*
X433382Y360466D03*
X438500Y364500D03*
X446000Y374500D03*
X438400Y382400D03*
X430000Y381000D03*
X431000Y406500D03*
Y416000D03*
Y411500D03*
X460000Y76000D03*
X448430Y89540D03*
X463500Y86500D03*
Y92000D03*
X458500Y86500D03*
X450000Y108200D03*
X454600Y108500D03*
X448500Y100500D03*
X462500Y117000D03*
X462000Y224500D03*
X461000Y234500D03*
X457500Y227500D03*
Y223500D03*
X449000Y232500D03*
Y227500D03*
X461000Y230000D03*
X462000Y250000D03*
X448500Y237500D03*
X457500Y250000D03*
X448500D03*
X457500Y237400D03*
X453000Y250000D03*
X457000Y258500D03*
X459500Y262000D03*
X461500Y268409D03*
X460000Y284500D03*
Y289500D03*
X460800Y294200D03*
X461000Y302500D03*
X464500Y298500D03*
X456500Y305500D03*
X454000Y312500D03*
X448500Y311500D03*
X461500Y311000D03*
X451000Y306500D03*
X459500Y322000D03*
X459000Y326000D03*
X450900Y330900D03*
X450500Y368500D03*
X453500Y381500D03*
X454000Y393500D03*
Y397000D03*
X450000Y407000D03*
Y416500D03*
Y411500D03*
X481000Y70700D03*
X478000Y78000D03*
X482000Y83500D03*
X465500Y78500D03*
X475500Y82500D03*
X470500D03*
X479867Y138867D03*
X481500Y182016D03*
X481000Y172500D03*
X479246Y178464D03*
X477500Y170500D03*
X478000Y198000D03*
X481500Y193000D03*
X480288Y203788D03*
X471000Y239000D03*
X477000D03*
X471000Y259200D03*
X477500Y259000D03*
X468500Y264500D03*
Y270000D03*
X471000Y347000D03*
X478500Y346000D03*
X481000Y341000D03*
X471400Y363300D03*
X470500Y391000D03*
X493700Y79161D03*
X496000Y85000D03*
X489400Y126300D03*
X493300Y121500D03*
X496000Y163000D03*
Y167500D03*
Y179258D03*
X484000Y166000D03*
X497000Y175000D03*
X485033Y174934D03*
X498060Y185500D03*
X496500Y192500D03*
X483871Y198241D03*
X496500Y197500D03*
X484000Y185500D03*
X497500Y214000D03*
X496000Y205500D03*
X485000Y202739D03*
X490500Y216750D03*
X492500Y226000D03*
X497500D03*
X497100Y244700D03*
X497200Y240600D03*
X492300Y240800D03*
X492500Y272200D03*
X491800Y277700D03*
X497000Y341000D03*
X495000Y346000D03*
X483501D03*
X488500D03*
X504000Y64500D03*
X508500D03*
X513200Y66000D03*
X503005Y99494D03*
X508000Y105500D03*
Y110500D03*
Y115500D03*
X503860Y124150D03*
X503900Y128690D03*
X503950Y143000D03*
X514500Y144000D03*
X503950Y133500D03*
X514500Y151000D03*
Y148000D03*
Y154000D03*
Y157000D03*
X501500Y192500D03*
X507000D03*
Y188500D03*
X515500Y201000D03*
X513000Y210500D03*
X511500Y206500D03*
X513500Y215500D03*
X509000D03*
X512100Y249500D03*
X507100Y240700D03*
X512100D03*
Y244700D03*
X502200Y240700D03*
X512100Y262500D03*
X512300Y254400D03*
X512200Y258700D03*
X512650Y268150D03*
X501000Y263500D03*
X511900Y276200D03*
X508950Y273250D03*
X506100Y280600D03*
X509000Y340500D03*
X504500D03*
X514000Y374000D03*
X505000Y379500D03*
X504500Y376000D03*
X507500Y394500D03*
X503500D03*
X521500Y60000D03*
X529500Y60500D03*
X526500Y67500D03*
X519500Y75500D03*
X533000Y87000D03*
Y82000D03*
X519500Y81500D03*
X520000Y87000D03*
X524900Y99000D03*
X522500Y114500D03*
X533500Y124500D03*
X534000Y160500D03*
X517000Y212500D03*
X533200Y220000D03*
X529800Y223000D03*
X528710Y227500D03*
X534000Y231500D03*
X525400Y247000D03*
X522000D03*
X530350Y257480D03*
X524300Y261700D03*
X523900Y257100D03*
X532500Y272500D03*
X523600Y281100D03*
X531000Y285500D03*
X526000Y295500D03*
X532900Y318900D03*
X527600D03*
X519000Y307500D03*
X532400Y340600D03*
Y345600D03*
X527100Y340600D03*
Y345600D03*
X517500Y374000D03*
X532200Y377700D03*
X523700Y384100D03*
X528200Y377700D03*
X523700D03*
X518000Y382500D03*
X527500Y389100D03*
X532100Y399000D03*
X527500Y397100D03*
Y393100D03*
X525176Y411925D03*
X522100Y416500D03*
X551500Y59597D03*
X543957Y60543D03*
X537000Y69000D03*
X549000Y63500D03*
Y78223D03*
X544300Y87100D03*
X549400Y81600D03*
X536500Y84500D03*
Y79000D03*
X534500Y130000D03*
Y136500D03*
X534600Y148300D03*
Y152000D03*
X544000Y159000D03*
X543520Y174970D03*
X542270Y169900D03*
X539770Y174900D03*
Y169900D03*
Y172400D03*
X542270D03*
X542500Y189500D03*
X538500D03*
X540900Y201500D03*
X543500Y205000D03*
X536900Y201500D03*
X545800Y216500D03*
X541000Y216400D03*
X537500Y232000D03*
X548300Y222600D03*
X546500Y240500D03*
X549000Y267500D03*
X551700Y256300D03*
X541000Y281500D03*
X539500Y292000D03*
X541346Y303507D03*
X542000Y296450D03*
X537500Y304000D03*
X538600Y318900D03*
X538100Y340600D03*
Y345600D03*
X539000Y370000D03*
X539300Y365100D03*
X539000Y360000D03*
X543000Y370000D03*
X543300Y365100D03*
X543000Y360000D03*
X548557Y387700D03*
X540600Y386300D03*
X538500Y407875D03*
X543000Y396700D03*
X548829Y416329D03*
X548500Y411000D03*
X538558Y413779D03*
X550369Y427558D03*
X538558D03*
X562500Y74600D03*
X560650Y70450D03*
X559941Y62120D03*
X563341Y62102D03*
X564350Y65350D03*
X559000Y85000D03*
X560200Y81500D03*
X559000Y88800D03*
X565933Y102000D03*
X562533Y102001D03*
X553000Y108500D03*
X568700Y204300D03*
X564700Y204400D03*
X554600Y202400D03*
X558900Y202500D03*
X566950Y220000D03*
X553800Y240200D03*
X560000Y240000D03*
X565400Y244700D03*
X562000Y254870D03*
X554400Y267500D03*
X561700Y320300D03*
X556700D03*
X562500Y336100D03*
Y326100D03*
X562000Y331600D03*
X563700Y352400D03*
X560000Y342100D03*
X568100Y366400D03*
Y361700D03*
X568326Y371200D03*
X563800Y390700D03*
X564500Y379000D03*
X560200Y386500D03*
X567500D03*
X568600Y376000D03*
Y380700D03*
X564400Y396700D03*
X567500Y403000D03*
X555000Y402000D03*
X567126Y417500D03*
X555315D03*
X562180Y413779D03*
Y427558D03*
X580500Y65800D03*
X580643Y60900D03*
X585900Y79600D03*
X586500Y107000D03*
Y112500D03*
X576459Y161971D03*
X575072Y165500D03*
X580500Y194500D03*
X583000Y192000D03*
X573200Y204300D03*
X586500Y230000D03*
X571000Y217900D03*
X576500Y219700D03*
X569943Y223300D03*
X585000Y226500D03*
X578900Y236600D03*
X581500Y267000D03*
X581400Y292250D03*
X583000Y297000D03*
X580300Y356700D03*
X576300Y371200D03*
X580200Y361700D03*
X580100Y366700D03*
X580300Y380700D03*
Y375700D03*
Y385700D03*
Y390700D03*
X576900Y403100D03*
X578937Y417500D03*
X572500Y413500D03*
X584000Y421900D03*
X573991Y427558D03*
X599000Y92500D03*
X588000Y96500D03*
X600850Y112350D03*
X592000Y127063D03*
X599500Y116500D03*
X592000Y136000D03*
Y141000D03*
Y146000D03*
Y163000D03*
Y151500D03*
Y157063D03*
Y173000D03*
Y178000D03*
Y168000D03*
X597703Y187000D03*
X587500Y190000D03*
X594003Y187000D03*
X602500Y183000D03*
X601550Y208450D03*
X596450Y210350D03*
X601953Y218853D03*
X590650Y245680D03*
X604000Y254500D03*
X591000Y271500D03*
Y278500D03*
Y291500D03*
X602500Y404000D03*
X591000D03*
X604000Y398000D03*
X597500Y421900D03*
X602559Y417500D03*
X590748Y418725D03*
X597613Y413779D03*
Y427558D03*
X616500Y194874D03*
X606902Y186000D03*
X610500Y190500D03*
X614100Y224100D03*
X610500Y227000D03*
X614100Y236400D03*
X618650Y249300D03*
X609500Y254500D03*
X614500Y398000D03*
Y403500D03*
X614370Y417500D03*
X609424Y413779D03*
Y427558D03*
X633500Y108000D03*
Y102000D03*
Y96500D03*
X637900Y116900D03*
X622000Y127063D03*
Y136000D03*
Y141500D03*
Y146500D03*
Y162000D03*
Y151600D03*
Y157000D03*
Y181500D03*
Y175500D03*
X622035Y167063D03*
X633500Y196874D03*
X628500Y189500D03*
X636000Y216142D03*
X627500Y205374D03*
X626989Y237989D03*
X633000Y286500D03*
X633500Y301500D03*
X647000Y108000D03*
Y113500D03*
G54D117*
G01X136000Y-65500D02*
Y-158000D01*
X506000D01*
Y-65500D01*
X136000D01*
G01X316000D02*
Y-158000D01*
G54D108*
X605315Y367519D03*
G54D60*
X255906Y309646D03*
Y412008D03*
X494094Y309646D03*
Y412008D03*
G54D15*
X29528Y36811D03*
Y373031D03*
X640039Y65354D03*
Y417835D03*
G54D24*
X55600Y165000D03*
X51400D03*
X61900Y279000D03*
X63100Y329000D03*
X58900D03*
X77900Y110000D03*
Y105000D03*
Y120000D03*
Y125000D03*
Y115000D03*
Y130000D03*
X74547Y179500D03*
X78747D03*
X74547Y175000D03*
X78747D03*
X74547Y193000D03*
X78747D03*
X74547Y197500D03*
X78747D03*
X74547Y188500D03*
X78747D03*
X74547Y184000D03*
X78747D03*
X68448Y266400D03*
X64248D03*
Y261400D03*
X68448D03*
X71400Y279000D03*
X75600D03*
X64248Y270900D03*
X68448D03*
X66100Y279000D03*
X70400Y320000D03*
X74600D03*
X70400Y324500D03*
X74600D03*
X82100Y110000D03*
Y105000D03*
Y120000D03*
Y125000D03*
Y115000D03*
Y130000D03*
X90700Y258048D03*
X94900D03*
X95048Y268300D03*
X90848D03*
X95100Y272800D03*
X90900D03*
X121570Y61360D03*
X117370D03*
Y65860D03*
X121570D03*
X117370Y75360D03*
X121570D03*
X117370Y70860D03*
X121570D03*
X130850Y65800D03*
Y61300D03*
X130870Y70800D03*
Y75300D03*
X122900Y375000D03*
X127100D03*
X135050Y65800D03*
Y61300D03*
X135070Y70800D03*
Y75300D03*
X148400Y295000D03*
X142500Y385100D03*
X146700D03*
X143500Y399100D03*
X147700D03*
X143500Y394600D03*
X147700D03*
Y414200D03*
X143500D03*
X152600Y295000D03*
X167000Y384100D03*
X165000Y409100D03*
X182400Y304000D03*
X181900Y319000D03*
X171200Y384100D03*
X169200Y409100D03*
X186600Y304000D03*
X186100Y319000D03*
X263700Y60500D03*
X259500D03*
Y65500D03*
X263700D03*
X289500Y320600D03*
Y325900D03*
X289600Y333200D03*
X299600Y57441D03*
X295400D03*
X299720Y66780D03*
X295520D03*
X299700Y62100D03*
X295500D03*
X293700Y320600D03*
Y325900D03*
X293800Y333200D03*
X312400Y164500D03*
X316600D03*
X312300Y180000D03*
X316500D03*
X316600Y169500D03*
X312400D03*
X312300Y175000D03*
X316500D03*
X316800Y196500D03*
X321000D03*
X316100Y189500D03*
X311900D03*
X316100Y185000D03*
X311900D03*
X316800Y201500D03*
X321000D03*
X316800Y206000D03*
X321000D03*
X316800Y211000D03*
X321000D03*
X315900Y216400D03*
X320100D03*
X315900Y220900D03*
X320100D03*
X315900Y234400D03*
X320100D03*
X315900Y229900D03*
X320100D03*
Y225400D03*
X315900D03*
Y247900D03*
X320100D03*
Y238900D03*
X315900D03*
X320100Y243400D03*
X315900D03*
Y252400D03*
X320100D03*
X315900Y256900D03*
X320100D03*
X329600Y216500D03*
X325400D03*
X330700Y388700D03*
X334900D03*
X328700Y413700D03*
X332900D03*
X352200Y383300D03*
X356400D03*
X349400Y378000D03*
X353600D03*
X356400Y403200D03*
X352200D03*
X356400Y398700D03*
X352200D03*
X356400Y407700D03*
X352200D03*
X359400Y419700D03*
X355200D03*
X376900Y97000D03*
X373100Y271000D03*
X368900D03*
X391100Y97000D03*
X386900D03*
X381100D03*
X392600Y268000D03*
X385800D03*
X381600D03*
X385800Y277500D03*
X381600D03*
X392600Y272500D03*
X385800D03*
X381600D03*
X393300Y309200D03*
X389100D03*
X383500D03*
X379300D03*
X383900Y381000D03*
X388100D03*
X383900Y375800D03*
X388100D03*
X410100Y97000D03*
X405900D03*
X396400D03*
X400600D03*
X396800Y268000D03*
Y272500D03*
X401500Y329100D03*
X397300D03*
X401500Y323900D03*
X397300D03*
X414500Y279200D03*
X418700D03*
X432200Y97300D03*
X436400D03*
X446000D03*
X441800D03*
X432450Y112300D03*
X436650D03*
X445850D03*
X441650D03*
X442600Y370000D03*
X438400D03*
X442600Y379000D03*
X438400D03*
X435400Y386500D03*
X439600D03*
X442600Y374500D03*
X438400D03*
X439600Y396500D03*
X435400D03*
X439600Y401500D03*
X435400D03*
Y391500D03*
X439600D03*
X435400Y406500D03*
X439600D03*
X435400Y411500D03*
X439600D03*
X456600Y284500D03*
X452400D03*
X456600Y289500D03*
X452400D03*
X456600Y294500D03*
X452400D03*
Y299500D03*
X456600D03*
X455100Y327000D03*
X450900D03*
X451200Y322000D03*
X455400D03*
X473600Y86500D03*
X469400D03*
X473600Y78500D03*
X469400D03*
X473600Y91500D03*
X469400D03*
X473600Y96500D03*
X469400D03*
X495900Y138500D03*
Y143000D03*
Y133500D03*
X488400Y163000D03*
X492600D03*
X488400Y167500D03*
X492600D03*
X488400Y176500D03*
X492600D03*
Y172000D03*
X488400D03*
Y197500D03*
X492600D03*
X488400Y211500D03*
X492600D03*
X488400Y202500D03*
X492600D03*
X488400Y207000D03*
X492600D03*
X500100Y138500D03*
Y143000D03*
Y133500D03*
X505600Y247400D03*
X501400D03*
X508400Y259700D03*
X504200D03*
X516200Y259200D03*
X508900Y377500D03*
X513100D03*
X524900Y76000D03*
X529100D03*
Y92000D03*
X524900D03*
Y82000D03*
X529100D03*
X524900Y87000D03*
X529100D03*
X520400Y259200D03*
X532000Y395700D03*
X544600Y69000D03*
X540400D03*
X546443Y396700D03*
X550643D03*
X536200Y395700D03*
X564900Y79200D03*
X569100D03*
X556900D03*
X552700D03*
X565400Y240000D03*
X563700Y356900D03*
X559500D03*
X560100Y391500D03*
X555900D03*
Y396000D03*
X560100D03*
X577100Y224500D03*
X572900D03*
X569600Y240000D03*
X576200Y351700D03*
X572000D03*
Y346700D03*
X576200D03*
Y356700D03*
X572000D03*
Y366700D03*
X576200D03*
X572000Y361700D03*
X576200D03*
Y385700D03*
X572000D03*
X576200Y380700D03*
X572000D03*
Y390700D03*
X576200D03*
X572000Y375700D03*
X576200D03*
X595600Y108000D03*
X591400D03*
X595600Y96500D03*
X591400D03*
Y112500D03*
X595600D03*
Y102500D03*
X591400D03*
X602900Y227000D03*
Y222500D03*
X594153Y223900D03*
X589953D03*
Y228402D03*
X594153D03*
X589953Y233000D03*
X594153D03*
X607100Y227000D03*
Y222500D03*
X637900Y96500D03*
Y102000D03*
Y108000D03*
Y113500D03*
X642100Y96500D03*
Y102000D03*
Y108000D03*
Y113500D03*
G54D51*
X158104Y391187D03*
Y402013D03*
X341796Y395787D03*
Y406613D03*
G54D33*
X75740Y339350D03*
X72000D03*
X68260D03*
Y350650D03*
X72000D03*
X75740D03*
X373240Y251350D03*
X369500D03*
X365760D03*
Y262650D03*
X369500D03*
X373240D03*
X630729Y220184D03*
X626989D03*
X623249D03*
Y231484D03*
X626989D03*
X630729D03*
G54D42*
X143567Y106043D03*
X146067Y268043D03*
X268567Y112143D03*
Y255943D03*
G54D118*
G01X329433Y-125500D02*
Y-133000D01*
X333167D01*
G01X340480D02*
Y-128000D01*
G01Y-128875D02*
X340107Y-128375D01*
X339547Y-128125D01*
X338893Y-128000D01*
X338240Y-128250D01*
X337680Y-128750D01*
X337307Y-129500D01*
X337120Y-130500D01*
X337307Y-131500D01*
X337680Y-132250D01*
X338240Y-132750D01*
X338893Y-133000D01*
X339547Y-132875D01*
X340107Y-132500D01*
X340480Y-132000D01*
G01X344340Y-135250D02*
X344900Y-135500D01*
X345647Y-135250D01*
X346113Y-134750D01*
X346487Y-134125D01*
X347047Y-132125D01*
X348260Y-128000D01*
G01X345273D02*
X347047Y-132125D01*
G01X352400Y-129625D02*
X355387D01*
X355107Y-128750D01*
X354640Y-128250D01*
X353987Y-128000D01*
X353333Y-128125D01*
X352773Y-128500D01*
X352400Y-129375D01*
X352213Y-130125D01*
Y-130875D01*
X352400Y-131625D01*
X352867Y-132375D01*
X353427Y-132875D01*
X354080Y-133000D01*
X354733Y-132750D01*
X355387Y-132000D01*
G01X359993Y-133000D02*
Y-128000D01*
G01Y-129000D02*
X360460Y-128500D01*
X360927Y-128125D01*
X361580Y-128000D01*
X362047Y-128125D01*
X362607Y-128500D01*
G01X368800Y-133250D02*
X368613Y-133125D01*
Y-132875D01*
X368800Y-132750D01*
X368987Y-132875D01*
Y-133125D01*
X368800Y-133250D01*
G01Y-129875D02*
X368613Y-129750D01*
Y-129500D01*
X368800Y-129375D01*
X368987Y-129500D01*
Y-129750D01*
X368800Y-129875D01*
G01X336747Y-120500D02*
Y-113000D01*
X338613D01*
X339360Y-113375D01*
X339920Y-113875D01*
X340387Y-114625D01*
X340760Y-115500D01*
X340853Y-116750D01*
X340760Y-118000D01*
X340387Y-118875D01*
X339920Y-119625D01*
X339360Y-120125D01*
X338613Y-120500D01*
X336747D01*
G01X347980D02*
Y-115500D01*
G01Y-116375D02*
X347607Y-115875D01*
X347047Y-115625D01*
X346393Y-115500D01*
X345740Y-115750D01*
X345180Y-116250D01*
X344807Y-117000D01*
X344620Y-118000D01*
X344807Y-119000D01*
X345180Y-119750D01*
X345740Y-120250D01*
X346393Y-120500D01*
X347047Y-120375D01*
X347607Y-120000D01*
X347980Y-119500D01*
G01X353800Y-113000D02*
Y-120500D01*
G01X352493Y-115500D02*
X355107D01*
G01X359900Y-117125D02*
X362887D01*
X362607Y-116250D01*
X362140Y-115750D01*
X361487Y-115500D01*
X360833Y-115625D01*
X360273Y-116000D01*
X359900Y-116875D01*
X359713Y-117625D01*
Y-118375D01*
X359900Y-119125D01*
X360367Y-119875D01*
X360927Y-120375D01*
X361580Y-120500D01*
X362233Y-120250D01*
X362887Y-119500D01*
G01X368800Y-120750D02*
X368613Y-120625D01*
Y-120375D01*
X368800Y-120250D01*
X368987Y-120375D01*
Y-120625D01*
X368800Y-120750D01*
G01Y-117375D02*
X368613Y-117250D01*
Y-117000D01*
X368800Y-116875D01*
X368987Y-117000D01*
Y-117250D01*
X368800Y-117375D01*
G01X382027Y-114250D02*
X382587Y-113500D01*
X383240Y-113125D01*
X383987Y-113000D01*
X384920Y-113250D01*
X385573Y-113875D01*
X385760Y-114625D01*
X385667Y-115375D01*
X385293Y-116000D01*
X383427Y-117250D01*
X382587Y-118125D01*
X382027Y-119375D01*
X381840Y-120500D01*
X385760D01*
G01X391300Y-113000D02*
X390553Y-113250D01*
X389993Y-113875D01*
X389620Y-114625D01*
X389340Y-115625D01*
X389247Y-116750D01*
X389340Y-117875D01*
X389620Y-118875D01*
X389993Y-119625D01*
X390553Y-120250D01*
X391300Y-120500D01*
X392047Y-120250D01*
X392607Y-119625D01*
X392980Y-118875D01*
X393260Y-117875D01*
X393353Y-116750D01*
X393260Y-115625D01*
X392980Y-114625D01*
X392607Y-113875D01*
X392047Y-113250D01*
X391300Y-113000D01*
G01X397027Y-114250D02*
X397587Y-113500D01*
X398240Y-113125D01*
X398987Y-113000D01*
X399920Y-113250D01*
X400573Y-113875D01*
X400760Y-114625D01*
X400667Y-115375D01*
X400293Y-116000D01*
X398427Y-117250D01*
X397587Y-118125D01*
X397027Y-119375D01*
X396840Y-120500D01*
X400760D01*
G01X404527Y-114250D02*
X405087Y-113500D01*
X405740Y-113125D01*
X406487Y-113000D01*
X407420Y-113250D01*
X408073Y-113875D01*
X408260Y-114625D01*
X408167Y-115375D01*
X407793Y-116000D01*
X405927Y-117250D01*
X405087Y-118125D01*
X404527Y-119375D01*
X404340Y-120500D01*
X408260D01*
G01X412587Y-118000D02*
X415013D01*
G01X421300Y-113000D02*
X420553Y-113250D01*
X419993Y-113875D01*
X419620Y-114625D01*
X419340Y-115625D01*
X419247Y-116750D01*
X419340Y-117875D01*
X419620Y-118875D01*
X419993Y-119625D01*
X420553Y-120250D01*
X421300Y-120500D01*
X422047Y-120250D01*
X422607Y-119625D01*
X422980Y-118875D01*
X423260Y-117875D01*
X423353Y-116750D01*
X423260Y-115625D01*
X422980Y-114625D01*
X422607Y-113875D01*
X422047Y-113250D01*
X421300Y-113000D01*
G01X427027Y-114250D02*
X427587Y-113500D01*
X428240Y-113125D01*
X428987Y-113000D01*
X429920Y-113250D01*
X430573Y-113875D01*
X430760Y-114625D01*
X430667Y-115375D01*
X430293Y-116000D01*
X428427Y-117250D01*
X427587Y-118125D01*
X427027Y-119375D01*
X426840Y-120500D01*
X430760D01*
G01X435087Y-118000D02*
X437513D01*
G01X442027Y-114250D02*
X442587Y-113500D01*
X443240Y-113125D01*
X443987Y-113000D01*
X444920Y-113250D01*
X445573Y-113875D01*
X445760Y-114625D01*
X445667Y-115375D01*
X445293Y-116000D01*
X443427Y-117250D01*
X442587Y-118125D01*
X442027Y-119375D01*
X441840Y-120500D01*
X445760D01*
G01X449247Y-119375D02*
X449807Y-120000D01*
X450460Y-120375D01*
X451300Y-120500D01*
X452140Y-120250D01*
X452793Y-119750D01*
X453260Y-118875D01*
X453353Y-117875D01*
X453167Y-116875D01*
X452700Y-116250D01*
X452047Y-115750D01*
X451393Y-115625D01*
X450740Y-115750D01*
X449900Y-116250D01*
X450180Y-113000D01*
X452700D01*
G01X336933Y-108000D02*
Y-100500D01*
X339267D01*
X340013Y-100875D01*
X340480Y-101375D01*
X340667Y-102375D01*
X340480Y-103375D01*
X339920Y-104000D01*
X339267Y-104375D01*
X336933D01*
G01X339267D02*
X340667Y-108000D01*
G01X344900Y-104625D02*
X347887D01*
X347607Y-103750D01*
X347140Y-103250D01*
X346487Y-103000D01*
X345833Y-103125D01*
X345273Y-103500D01*
X344900Y-104375D01*
X344713Y-105125D01*
Y-105875D01*
X344900Y-106625D01*
X345367Y-107375D01*
X345927Y-107875D01*
X346580Y-108000D01*
X347233Y-107750D01*
X347887Y-107000D01*
G01X352120Y-103000D02*
X353800Y-108000D01*
X355480Y-103000D01*
G01X368800Y-108250D02*
X368613Y-108125D01*
Y-107875D01*
X368800Y-107750D01*
X368987Y-107875D01*
Y-108125D01*
X368800Y-108250D01*
G01Y-104875D02*
X368613Y-104750D01*
Y-104500D01*
X368800Y-104375D01*
X368987Y-104500D01*
Y-104750D01*
X368800Y-104875D01*
G01X383800Y-100500D02*
X383053Y-100750D01*
X382493Y-101375D01*
X382120Y-102125D01*
X381840Y-103125D01*
X381747Y-104250D01*
X381840Y-105375D01*
X382120Y-106375D01*
X382493Y-107125D01*
X383053Y-107750D01*
X383800Y-108000D01*
X384547Y-107750D01*
X385107Y-107125D01*
X385480Y-106375D01*
X385760Y-105375D01*
X385853Y-104250D01*
X385760Y-103125D01*
X385480Y-102125D01*
X385107Y-101375D01*
X384547Y-100750D01*
X383800Y-100500D01*
G01X391300Y-108000D02*
Y-100500D01*
X390180Y-102000D01*
G01Y-108000D02*
X392420D01*
G01X336933Y-95500D02*
Y-88000D01*
X339173D01*
X339920Y-88375D01*
X340480Y-89250D01*
X340667Y-90250D01*
X340480Y-91250D01*
X340013Y-92000D01*
X339173Y-92375D01*
X336933D01*
G01X344620Y-95750D02*
X347980Y-88000D01*
G01X351653Y-95500D02*
Y-88000D01*
X355947Y-95500D01*
Y-88000D01*
G01X368800Y-95750D02*
X368613Y-95625D01*
Y-95375D01*
X368800Y-95250D01*
X368987Y-95375D01*
Y-95625D01*
X368800Y-95750D01*
G01Y-92375D02*
X368613Y-92250D01*
Y-92000D01*
X368800Y-91875D01*
X368987Y-92000D01*
Y-92250D01*
X368800Y-92375D01*
G01X381933Y-95500D02*
Y-88000D01*
X384267D01*
X385013Y-88375D01*
X385480Y-88875D01*
X385667Y-89875D01*
X385480Y-90875D01*
X384920Y-91500D01*
X384267Y-91875D01*
X381933D01*
G01X384267D02*
X385667Y-95500D01*
G01X392420D02*
Y-88000D01*
X388967Y-93375D01*
X393633D01*
G01X398800Y-88000D02*
X398053Y-88250D01*
X397493Y-88875D01*
X397120Y-89625D01*
X396840Y-90625D01*
X396747Y-91750D01*
X396840Y-92875D01*
X397120Y-93875D01*
X397493Y-94625D01*
X398053Y-95250D01*
X398800Y-95500D01*
X399547Y-95250D01*
X400107Y-94625D01*
X400480Y-93875D01*
X400760Y-92875D01*
X400853Y-91750D01*
X400760Y-90625D01*
X400480Y-89625D01*
X400107Y-88875D01*
X399547Y-88250D01*
X398800Y-88000D01*
G01X406300D02*
X405553Y-88250D01*
X404993Y-88875D01*
X404620Y-89625D01*
X404340Y-90625D01*
X404247Y-91750D01*
X404340Y-92875D01*
X404620Y-93875D01*
X404993Y-94625D01*
X405553Y-95250D01*
X406300Y-95500D01*
X407047Y-95250D01*
X407607Y-94625D01*
X407980Y-93875D01*
X408260Y-92875D01*
X408353Y-91750D01*
X408260Y-90625D01*
X407980Y-89625D01*
X407607Y-88875D01*
X407047Y-88250D01*
X406300Y-88000D01*
G01X412027Y-92375D02*
X412680Y-91500D01*
X413240Y-91000D01*
X413987Y-90750D01*
X414640Y-91000D01*
X415107Y-91500D01*
X415480Y-92250D01*
X415573Y-93125D01*
X415480Y-93875D01*
X415107Y-94625D01*
X414547Y-95250D01*
X413893Y-95500D01*
X413147Y-95250D01*
X412493Y-94500D01*
X412120Y-93375D01*
X412027Y-92125D01*
X412213Y-90500D01*
X412493Y-89625D01*
X412960Y-88750D01*
X413613Y-88125D01*
X414267Y-88000D01*
X414920Y-88250D01*
X415387Y-88875D01*
G01X420087Y-93000D02*
X422513D01*
G01X429547Y-91500D02*
X429920Y-91125D01*
X430200Y-90500D01*
X430387Y-89625D01*
X430200Y-88875D01*
X429827Y-88375D01*
X429173Y-88000D01*
X426653D01*
Y-95500D01*
X429733D01*
X430387Y-95000D01*
X430760Y-94250D01*
X430947Y-93375D01*
X430760Y-92500D01*
X430200Y-91750D01*
X429547Y-91500D01*
X426653D01*
G01X436300Y-88000D02*
X435553Y-88250D01*
X434993Y-88875D01*
X434620Y-89625D01*
X434340Y-90625D01*
X434247Y-91750D01*
X434340Y-92875D01*
X434620Y-93875D01*
X434993Y-94625D01*
X435553Y-95250D01*
X436300Y-95500D01*
X437047Y-95250D01*
X437607Y-94625D01*
X437980Y-93875D01*
X438260Y-92875D01*
X438353Y-91750D01*
X438260Y-90625D01*
X437980Y-89625D01*
X437607Y-88875D01*
X437047Y-88250D01*
X436300Y-88000D01*
G01X443800D02*
X443053Y-88250D01*
X442493Y-88875D01*
X442120Y-89625D01*
X441840Y-90625D01*
X441747Y-91750D01*
X441840Y-92875D01*
X442120Y-93875D01*
X442493Y-94625D01*
X443053Y-95250D01*
X443800Y-95500D01*
X444547Y-95250D01*
X445107Y-94625D01*
X445480Y-93875D01*
X445760Y-92875D01*
X445853Y-91750D01*
X445760Y-90625D01*
X445480Y-89625D01*
X445107Y-88875D01*
X444547Y-88250D01*
X443800Y-88000D01*
G01X451300D02*
X450553Y-88250D01*
X449993Y-88875D01*
X449620Y-89625D01*
X449340Y-90625D01*
X449247Y-91750D01*
X449340Y-92875D01*
X449620Y-93875D01*
X449993Y-94625D01*
X450553Y-95250D01*
X451300Y-95500D01*
X452047Y-95250D01*
X452607Y-94625D01*
X452980Y-93875D01*
X453260Y-92875D01*
X453353Y-91750D01*
X453260Y-90625D01*
X452980Y-89625D01*
X452607Y-88875D01*
X452047Y-88250D01*
X451300Y-88000D01*
G01X458800Y-95500D02*
Y-88000D01*
X457680Y-89500D01*
G01Y-95500D02*
X459920D01*
G01X465087Y-93000D02*
X467513D01*
G01X473800Y-88000D02*
X473053Y-88250D01*
X472493Y-88875D01*
X472120Y-89625D01*
X471840Y-90625D01*
X471747Y-91750D01*
X471840Y-92875D01*
X472120Y-93875D01*
X472493Y-94625D01*
X473053Y-95250D01*
X473800Y-95500D01*
X474547Y-95250D01*
X475107Y-94625D01*
X475480Y-93875D01*
X475760Y-92875D01*
X475853Y-91750D01*
X475760Y-90625D01*
X475480Y-89625D01*
X475107Y-88875D01*
X474547Y-88250D01*
X473800Y-88000D01*
G01X479527Y-89250D02*
X480087Y-88500D01*
X480740Y-88125D01*
X481487Y-88000D01*
X482420Y-88250D01*
X483073Y-88875D01*
X483260Y-89625D01*
X483167Y-90375D01*
X482793Y-91000D01*
X480927Y-92250D01*
X480087Y-93125D01*
X479527Y-94375D01*
X479340Y-95500D01*
X483260D01*
G01X384340Y-132000D02*
X385087Y-132625D01*
X385927Y-133000D01*
X386673D01*
X387420Y-132625D01*
X387980Y-132000D01*
X388260Y-131125D01*
X388073Y-130250D01*
X387607Y-129500D01*
X386767Y-129000D01*
X385647Y-128750D01*
X384993Y-128250D01*
X384713Y-127375D01*
X384900Y-126500D01*
X385367Y-125875D01*
X386020Y-125500D01*
X386673D01*
X387327Y-125750D01*
X387887Y-126375D01*
G01X393800Y-133000D02*
X393053Y-132875D01*
X392400Y-132375D01*
X391840Y-131625D01*
X391467Y-130750D01*
X391280Y-129750D01*
Y-128750D01*
X391467Y-127750D01*
X391840Y-126875D01*
X392400Y-126125D01*
X393053Y-125625D01*
X393800Y-125500D01*
X394547Y-125625D01*
X395200Y-126125D01*
X395760Y-126875D01*
X396133Y-127750D01*
X396320Y-128750D01*
Y-129750D01*
X396133Y-130750D01*
X395760Y-131625D01*
X395200Y-132375D01*
X394547Y-132875D01*
X393800Y-133000D01*
G01X399433Y-125500D02*
Y-133000D01*
X403167D01*
G01X406747D02*
Y-125500D01*
X408613D01*
X409360Y-125875D01*
X409920Y-126375D01*
X410387Y-127125D01*
X410760Y-128000D01*
X410853Y-129250D01*
X410760Y-130500D01*
X410387Y-131375D01*
X409920Y-132125D01*
X409360Y-132625D01*
X408613Y-133000D01*
X406747D01*
G01X418167D02*
X414433D01*
Y-125500D01*
X418167D01*
G01X416673Y-129125D02*
X414433D01*
G01X421933Y-133000D02*
Y-125500D01*
X424267D01*
X425013Y-125875D01*
X425480Y-126375D01*
X425667Y-127375D01*
X425480Y-128375D01*
X424920Y-129000D01*
X424267Y-129375D01*
X421933D01*
G01X424267D02*
X425667Y-133000D01*
G01X428873D02*
Y-125500D01*
X431300Y-131750D01*
X433727Y-125500D01*
Y-133000D01*
G01X436467D02*
X438800Y-125500D01*
X441133Y-133000D01*
G01X440293Y-130375D02*
X437307D01*
G01X444340Y-132000D02*
X445087Y-132625D01*
X445927Y-133000D01*
X446673D01*
X447420Y-132625D01*
X447980Y-132000D01*
X448260Y-131125D01*
X448073Y-130250D01*
X447607Y-129500D01*
X446767Y-129000D01*
X445647Y-128750D01*
X444993Y-128250D01*
X444713Y-127375D01*
X444900Y-126500D01*
X445367Y-125875D01*
X446020Y-125500D01*
X446673D01*
X447327Y-125750D01*
X447887Y-126375D01*
G01X451747Y-133000D02*
Y-125500D01*
G01X455293D02*
X451747Y-130125D01*
G01X455853Y-133000D02*
X453333Y-128000D01*
G01X468800Y-125500D02*
Y-133000D01*
G01X466653Y-125500D02*
X470947D01*
G01X476300Y-133000D02*
X475553Y-132875D01*
X474900Y-132375D01*
X474340Y-131625D01*
X473967Y-130750D01*
X473780Y-129750D01*
Y-128750D01*
X473967Y-127750D01*
X474340Y-126875D01*
X474900Y-126125D01*
X475553Y-125625D01*
X476300Y-125500D01*
X477047Y-125625D01*
X477700Y-126125D01*
X478260Y-126875D01*
X478633Y-127750D01*
X478820Y-128750D01*
Y-129750D01*
X478633Y-130750D01*
X478260Y-131625D01*
X477700Y-132375D01*
X477047Y-132875D01*
X476300Y-133000D01*
G01X481933D02*
Y-125500D01*
X484173D01*
X484920Y-125875D01*
X485480Y-126750D01*
X485667Y-127750D01*
X485480Y-128750D01*
X485013Y-129500D01*
X484173Y-129875D01*
X481933D01*
G54D52*
X165781Y391187D03*
Y402013D03*
X170112Y391187D03*
X167946D03*
Y402013D03*
X170112D03*
X334119Y395787D03*
X331954D03*
X329788D03*
Y406613D03*
X331954D03*
X334119D03*
G54D43*
X146000Y300700D03*
Y307300D03*
X218600Y403800D03*
Y410400D03*
X223600Y382800D03*
Y389400D03*
X226100Y403800D03*
Y410400D03*
X340000Y371800D03*
Y365200D03*
X332000Y371800D03*
Y365200D03*
X351500Y164800D03*
Y158200D03*
X348000Y371800D03*
Y365200D03*
X370500Y164800D03*
Y158200D03*
X372900Y287000D03*
Y280400D03*
X373200Y295200D03*
Y301800D03*
X445500Y267200D03*
Y273800D03*
X505000Y383700D03*
Y390300D03*
X535000Y178700D03*
Y185300D03*
X525400Y373800D03*
Y367200D03*
X533600Y373800D03*
Y367200D03*
X539000Y159700D03*
Y166300D03*
X538500Y205700D03*
Y212300D03*
X557500Y93200D03*
Y99800D03*
X576000Y208700D03*
Y215300D03*
X622500Y197074D03*
Y203674D03*
G54D25*
X57100Y389900D03*
Y384500D03*
X145500Y313800D03*
Y319200D03*
X176000Y313300D03*
Y318700D03*
X349100Y250900D03*
Y256300D03*
X493300Y252000D03*
Y246600D03*
X512000Y390700D03*
Y385300D03*
X539500Y222900D03*
Y228300D03*
X570000Y93300D03*
Y98700D03*
G54D70*
X355189Y188543D03*
X353614D03*
X355189Y194555D03*
X353614D03*
G54D61*
X275400Y57941D03*
X284800D03*
Y63059D03*
X275400D03*
Y60500D03*
G54D109*
X608450Y100660D03*
Y108340D03*
Y105780D03*
Y103220D03*
X626550Y108340D03*
Y100660D03*
Y103220D03*
Y105780D03*
G54D16*
X19878Y36811D03*
X22704Y29987D03*
Y43635D03*
X22834Y340080D03*
X26378D03*
X28150Y343150D03*
X24606D03*
X19878Y373031D03*
X22704Y366207D03*
Y379855D03*
X29528Y27161D03*
X36352Y29987D03*
X39178Y36811D03*
X36352Y43635D03*
X29528Y46461D03*
X29922Y340080D03*
X33466D03*
X37010D03*
X40554D03*
X44098D03*
X45870Y343150D03*
X42326D03*
X38782D03*
X35238D03*
X31694D03*
X29528Y363381D03*
X36352Y366207D03*
X39178Y373031D03*
X36352Y379855D03*
X29528Y382681D03*
X633215Y58530D03*
Y72178D03*
X630389Y65354D03*
X633215Y424659D03*
X630389Y417835D03*
X633215Y411011D03*
X640039Y55704D03*
X646863Y58530D03*
X649689Y65354D03*
X646863Y72178D03*
X640039Y75004D03*
Y408185D03*
X646863Y411011D03*
X649689Y417835D03*
X646863Y424659D03*
X640039Y427485D03*
G54D34*
X69300Y373600D03*
X87300D03*
G54D119*
G01X658071Y284646D02*
G03X660039Y286614I0J1968D01*
G01Y433661D01*
G03X656102Y437598I-3937J0D01*
G01X3937D01*
G03X0Y433661I0J-3937D01*
G01Y21654D01*
G03X3937Y17717I3937J0D01*
G01X55118D01*
G03X59055Y21654I0J3937D01*
G01Y46260D01*
G02X62992Y50197I3937J0D01*
G01X127362D01*
G02X131299Y46260I0J-3937D01*
G01Y21654D01*
G03X135236Y17717I3937J0D01*
G01X158858D01*
G03X162795Y21654I0J3937D01*
G01Y43012D01*
G02X177165I7185J0D01*
G01Y1969D01*
X179134Y0D01*
X219291D01*
X221260Y1969D01*
Y29331D01*
G02X228740I3740J0D01*
G01Y1969D01*
X230709Y0D01*
X310236D01*
X312205Y1969D01*
Y46260D01*
G02X316142Y50197I3937J0D01*
G01X656102D01*
G03X660039Y54134I0J3937D01*
G01Y237500D01*
G03X658071Y239469I-1969J1D01*
G01X657211D01*
G02X655243Y241437I0J1968D01*
G01Y282677D01*
G02X657211Y284646I1968J0D01*
G01X658071D01*
G01X145964Y-110118D02*
G03I-634J0D01*
G01X149695D02*
G03I-1038J0D01*
G01X168013Y-137456D02*
G03I-634J0D01*
G01X155900Y-133655D02*
G03I-632J0D01*
G01X161735Y-128639D02*
G03I-1458J0D01*
G01X158530Y-131428D02*
G03I-1041J0D01*
G01X158461Y-119126D02*
G03I-1283J0D01*
G01X162690Y-117490D02*
G03I-1584J0D01*
G01X169809Y-121292D02*
G03I-2180J0D01*
G01X165531Y-125255D02*
G03I-1869J0D01*
G01X167813Y-115513D02*
G03I-1971J0D01*
G01X154775Y-120500D02*
G03I-892J0D01*
G01X162681Y-102774D02*
G03I-1584J0D01*
G01X158451Y-101149D02*
G03I-1283J0D01*
G01X159258Y-110118D02*
G03I-1868J0D01*
G01X169812Y-98951D02*
G03I-2180J0D01*
G01X167802Y-104739D02*
G03I-1971J0D01*
G01X165183Y-110118D02*
G03I-2180J0D01*
G01X171881D02*
G03I-2642J0D01*
G01X152135Y-98681D02*
G03I-632J0D01*
G01X154064Y-110118D02*
G03I-1460J0D01*
G01X154764Y-99775D02*
G03I-892J0D01*
G01X158530Y-88809D02*
G03I-1041J0D01*
G01X161742Y-91601D02*
G03I-1458J0D01*
G01X165531Y-94981D02*
G03I-1869J0D01*
G01X171080Y-131739D02*
G03I-1282J0D01*
G01X169322Y-135033D02*
G03I-892J0D01*
G01X180669Y-131528D02*
G03I-1870J0D01*
G01X180255Y-136311D02*
G03I-1456J0D01*
G01X179841Y-140261D02*
G03I-1042J0D01*
G01X179433Y-143587D02*
G03I-634J0D01*
G01X181439Y-119680D02*
G03I-2640J0D01*
G01X175373Y-123081D02*
G03I-1968J0D01*
G01X173018Y-127816D02*
G03I-1584J0D01*
G01X174681Y-116876D02*
G03I-2640J0D01*
G01X180979Y-125917D02*
G03I-2180J0D01*
G01X186177Y-123075D02*
G03I-1971J0D01*
G01X188199Y-116876D02*
G03I-2640J0D01*
G01X175452Y-97124D02*
G03I-1968J0D01*
G01X186225Y-97178D02*
G03I-1971J0D01*
G01X181439Y-100556D02*
G03I-2640J0D01*
G01X174681Y-103361D02*
G03I-2640J0D01*
G01X188199D02*
G03I-2640J0D01*
G01X179841Y-79975D02*
G03I-1042J0D01*
G01X171217Y-88444D02*
G03I-1282J0D01*
G01X173123Y-92378D02*
G03I-1584J0D01*
G01X180255Y-83924D02*
G03I-1456J0D01*
G01X180669Y-88708D02*
G03I-1870J0D01*
G01X180979Y-94320D02*
G03I-2180J0D01*
G01X179433Y-76648D02*
G03I-634J0D01*
G01X191096Y-134658D02*
G03I-892J0D01*
G01X192135Y-136781D02*
G03I-631J0D01*
G01X198775Y-128635D02*
G03I-1458J0D01*
G01X195808Y-125255D02*
G03I-1869J0D01*
G01X200547Y-113952D02*
G03X203345Y-117196I7247J3422D01*
G01X192148Y-121285D02*
G03I-2180J0D01*
G01X187928Y-127802D02*
G03I-1584J0D01*
G01X189667Y-131511D02*
G03I-1283J0D01*
G01X200699Y-105836D02*
G03X200547Y-113953I8974J-4228D01*
G01X208284Y-101612D02*
G03X200698Y-105835I-219J-8531D01*
G01X192148Y-98951D02*
G03I-2180J0D01*
G01X191108Y-82727D02*
G03I-634J0D01*
G01X190184Y-85250D02*
G03I-893J0D01*
G01X195808Y-94981D02*
G03I-1869J0D01*
G01X187839Y-92457D02*
G03I-1584J0D01*
G01X189190Y-88538D02*
G03I-1283J0D01*
G01X214259Y-115661D02*
G03X213314Y-114453I-714J415D01*
G01X202049Y-108260D02*
G03X205722Y-116181I7039J-1548D01*
G01X218075Y-112869D02*
G03X219083Y-115752I4343J-99D01*
G01X208854Y-116658D02*
G03X213313Y-114452I-2485J10632D01*
G01X208470Y-118462D02*
G03X214261Y-115663I-1122J9711D01*
G01X203346Y-117195D02*
G03X208470Y-118461I4545J7394D01*
G01X205721Y-116179D02*
G03X208853Y-116659I2561J6250D01*
G01X215903Y-114020D02*
G03X219079Y-118061I6190J1597D01*
G01X215904Y-114020D02*
Y-111835D01*
G01X227413Y-112869D02*
X218074D01*
G01X214175Y-103951D02*
G03X208283Y-101613I-6403J-7542D01*
G01X213150Y-105147D02*
G03X214175Y-103951I410J686D01*
G01X213152Y-105146D02*
G03X208030Y-103430I-5122J-6786D01*
G01X208029Y-103429D02*
G03X202049Y-108259I-48J-6058D01*
G01X225189Y-111399D02*
G03X218071I-3559J159D01*
G01X218070Y-111418D02*
Y-111399D01*
G01X225188Y-111418D02*
X218070D01*
G01X227412Y-111835D02*
G03X215906I-5753J223D01*
G01X230059Y-117625D02*
Y-102034D01*
G01X230060Y-117626D02*
G03X232080I1010J239D01*
G01X226590Y-116472D02*
G03X225311Y-115210I-817J451D01*
G01X234673Y-114020D02*
G03X237849Y-118061I6190J1597D01*
G01X232081Y-102041D02*
Y-117625D01*
G01X219083Y-115753D02*
G03X225311Y-115211I2844J3371D01*
G01X219079Y-118060D02*
G03X226591Y-116473I2662J5972D01*
G01X227413Y-111835D02*
Y-112869D01*
G01X232080Y-102041D02*
G03X230060Y-102034I-1011J-236D01*
G01X225188Y-111399D02*
Y-111418D01*
G01X234675Y-114020D02*
Y-111835D01*
G01X246181D02*
G03X234675I-5753J223D01*
G01X252849Y-116771D02*
G03X254892Y-115895I-74J2994D01*
G01X236844Y-112869D02*
G03X237852Y-115752I4343J-99D01*
G01X237848Y-118060D02*
G03X245360Y-116473I2662J5972D01*
G01X245358Y-116472D02*
G03X244079Y-115210I-817J451D01*
G01X237852Y-115753D02*
G03X244080Y-115211I2844J3371D01*
G01X249566Y-115529D02*
G03X252307Y-116760I2985J2980D01*
G01Y-116761D02*
G03X252849Y-116772I366J4691D01*
G01X250282Y-118087D02*
G03X254318Y-118340I2605J9244D01*
G01X247897Y-116444D02*
G03X250283Y-118086I3752J2898D01*
G01X249568Y-115529D02*
G03X247898Y-116443I-748J-616D01*
G01X255608Y-108618D02*
G03X253612Y-107689I-3116J-4086D01*
G01X246181Y-111835D02*
Y-112869D01*
G01D02*
X236844D01*
G01X255002Y-114328D02*
G03X252723Y-112986I-3540J-3405D01*
G01X249955Y-112030D02*
G03X252723Y-112985I8208J19302D01*
G01X243957Y-111399D02*
Y-111418D01*
G01X243958Y-111399D02*
G03X236840I-3559J159D01*
G01X236841Y-111418D02*
Y-111399D01*
G01X243957Y-111418D02*
X236841D01*
G01X248537Y-109748D02*
G03X249956Y-112031I2652J66D01*
G01X248537Y-108250D02*
Y-109748D01*
G01X250179Y-106359D02*
G03X248537Y-108249I2747J-4045D01*
G01X256884Y-107368D02*
G03X250178Y-106359I-4153J-4811D01*
G01X253611Y-107689D02*
G03X251080Y-107949I-869J-3992D01*
G01X251081Y-107948D02*
G03X250837Y-110104I805J-1183D01*
G01Y-110106D02*
G03X254306Y-111513I5270J8013D01*
G01X260954Y-116041D02*
Y-107954D01*
G01X254892Y-115895D02*
G03X255001Y-114328I-764J840D01*
G01X269619Y-117484D02*
Y-106797D01*
G01X269620Y-117484D02*
G03X271926I1153J198D01*
G01X266864Y-117375D02*
G03X266002Y-116329I-764J249D01*
G01X262978Y-115462D02*
G03X266002Y-116329I2046J1428D01*
G01X260955Y-116043D02*
G03X264164Y-118351I2956J725D01*
G01X265463Y-118350D02*
X264165D01*
G01X265464Y-118352D02*
G03X266864Y-117374I-24J1525D01*
G01X256906Y-116470D02*
G03X257054Y-113728I-3143J1545D01*
G01X254317Y-118340D02*
G03X256906Y-116470I-1259J4470D01*
G01X262978Y-107954D02*
Y-115463D01*
G01X257054Y-113729D02*
G03X254307Y-111513I-3470J-1490D01*
G01X271969Y-102342D02*
G03I-1194J0D01*
G01X271926Y-106797D02*
G03X269620I-1153J-409D01*
G01X266003Y-107954D02*
X262978D01*
G01X266004Y-107955D02*
G03X266008Y-105932I-177J1012D01*
G01X262978D02*
X266008D01*
G01X262971Y-103419D02*
X262978Y-105932D01*
G01X262972Y-103418D02*
G03X260954Y-103491I-1005J-141D01*
G01Y-105932D02*
Y-103492D01*
G01X259930Y-105932D02*
X260954D01*
G01X259930D02*
G03X259981Y-107955I298J-1005D01*
G01X260954Y-107954D02*
X259982D01*
G01X255606Y-108620D02*
G03X256885Y-107367I599J667D01*
G01X290671Y-110842D02*
G03X290703Y-118351I860J-3751D01*
G01X276837Y-114305D02*
G03X278891Y-116297I4069J2141D01*
G01X274529Y-113568D02*
G03X275888Y-116443I5718J944D01*
G01X275887D02*
G03X279572Y-118352I4392J3967D01*
G01X281425Y-118350D02*
X279571D01*
G01X281425D02*
G03X284525Y-117161I0J4636D01*
G01X285201Y-116508D02*
X284524Y-117161D01*
G01X285201Y-116508D02*
G03X283966Y-115211I-695J574D01*
G01X281510Y-116675D02*
G03X283966Y-115212I-989J4453D01*
G01X278889Y-116297D02*
G03X281508Y-116677I1946J4197D01*
G01X271926Y-106797D02*
Y-117484D01*
G01X274529Y-113566D02*
Y-111839D01*
G01X276446Y-112943D02*
G03X276837Y-114305I4162J458D01*
G01X276445Y-112066D02*
Y-112943D01*
G01X283833Y-109274D02*
G03X285403Y-108106I585J852D01*
G01X285402D02*
G03X280919Y-105777I-4776J-3714D01*
G01X279541D02*
X280919D01*
G01X279540D02*
G03X274999Y-109274I1260J-6333D01*
G01X274998D02*
G03X274529Y-111839I9988J-3152D01*
G01X276849Y-109932D02*
G03X276446Y-112066I5467J-2137D01*
G01X280036Y-107542D02*
G03X276849Y-109933I664J-4205D01*
G01X282662Y-108199D02*
G03X280037Y-107539I-2313J-3650D01*
G01X283833Y-109275D02*
G03X282662Y-108202I-9277J-8949D01*
G01X294457Y-116619D02*
G03Y-112289I-51J2165D01*
G01X291853Y-116620D02*
X294456D01*
G01X291853Y-112289D02*
G03Y-116619I195J-2165D01*
G01X294165Y-118350D02*
X290701D01*
G01X294165D02*
G03X296471Y-117226I-1088J5161D01*
G01X296473Y-117625D02*
Y-117226D01*
G01X296474Y-117627D02*
G03X298494I1010J185D01*
G01X298495Y-109394D02*
Y-117625D01*
G01X301067Y-108534D02*
Y-106508D01*
G01X301615Y-108534D02*
X301067D01*
G01X301615Y-106508D02*
Y-108534D01*
G01X302461Y-106508D02*
X301615D01*
G01X302461Y-106001D02*
Y-106508D01*
G01X300223Y-106001D02*
X302461D01*
G01X300223Y-106508D02*
Y-106001D01*
G01X301067Y-106508D02*
X300223D01*
G01X305164Y-106001D02*
X304731D01*
G01X305713Y-108544D02*
X305164Y-106001D01*
G01X305171Y-108544D02*
X305713D01*
G01X304889Y-106871D02*
X305171Y-108544D01*
G01X304309D02*
X304889Y-106871D01*
G01X304086Y-108544D02*
X304309D01*
G01X303501Y-106887D02*
X304086Y-108544D01*
G01X303226D02*
X303501Y-106887D01*
G01X302698Y-108544D02*
X303226D01*
G01X303243Y-106001D02*
X302698Y-108544D01*
G01X303648Y-106001D02*
X303243D01*
G01X304192Y-107632D02*
X303648Y-106001D01*
G01X304731D02*
X304192Y-107632D01*
G01X294456Y-112288D02*
X291853D01*
G01X296473Y-110841D02*
Y-109686D01*
G01X296472Y-110841D02*
G03X292878Y-110536I-3256J-17043D01*
G01X292879Y-110535D02*
G03X290670Y-110842I280J-10112D01*
G01X298496Y-109394D02*
G03X295031Y-105933I-3962J-501D01*
G01X291563Y-105932D02*
X295031D01*
G01X291562D02*
G03X289112Y-107085I584J-4421D01*
G01Y-107086D02*
G03X289820Y-108520I585J-603D01*
G01X290987Y-107954D02*
G03X289821Y-108520I1446J-4464D01*
G01X294740Y-107954D02*
X290987D01*
G01X296473Y-109686D02*
G03X294742Y-107955I-1598J133D01*
G54D71*
X357000Y233243D03*
Y238557D03*
G54D26*
X73662Y70850D03*
X76221D03*
X78780D03*
X73662Y94750D03*
X76221D03*
X78780D03*
X81339Y70850D03*
Y94750D03*
G54D44*
X166220Y59000D03*
Y64000D03*
Y69000D03*
Y74000D03*
X188320Y59000D03*
Y64000D03*
Y69000D03*
Y74000D03*
G54D53*
X160860Y390104D03*
Y403096D03*
X339040Y407696D03*
Y394704D03*
G54D62*
X276986Y175184D03*
Y177152D03*
Y179121D03*
Y181089D03*
Y185026D03*
Y186995D03*
Y188963D03*
Y190932D03*
Y183058D03*
Y192900D03*
X292734Y175184D03*
Y177152D03*
Y179121D03*
Y181089D03*
Y186995D03*
Y188963D03*
Y190932D03*
Y192900D03*
Y183058D03*
Y185026D03*
G54D35*
X95750Y65360D03*
Y72840D03*
Y69100D03*
X107050Y72840D03*
Y65360D03*
G54D17*
X16039Y71260D03*
Y128346D03*
Y185433D03*
Y242520D03*
G54D80*
X395588Y288533D03*
G54D72*
X348100Y323500D03*
Y328500D03*
Y338500D03*
Y333500D03*
X376900D03*
Y338500D03*
Y323500D03*
Y328500D03*
G54D18*
X27250Y95650D03*
X19750Y104350D03*
X27250D03*
X19750Y218350D03*
X27250D03*
Y209650D03*
G54D81*
X400559Y340560D03*
X398000D03*
X395441D03*
Y348040D03*
X398000D03*
X400559D03*
X420059Y340760D03*
X417500D03*
X414941D03*
Y348240D03*
X417500D03*
X420059D03*
G54D36*
X95000Y84500D03*
X110500Y414500D03*
X578000Y116500D03*
G54D90*
X474000Y243650D03*
Y254150D03*
G54D27*
X70500Y142244D03*
X80500D03*
X70500Y162756D03*
X80500D03*
G54D45*
X162033Y297112D03*
X504833Y266312D03*
X556533Y63512D03*
G54D63*
X305708Y15731D03*
G54D54*
X166962Y397880D03*
Y395320D03*
X332938Y399920D03*
Y402480D03*
G54D64*
X304250Y322543D03*
Y325102D03*
Y335339D03*
Y327661D03*
Y332780D03*
Y337898D03*
Y330220D03*
Y340457D03*
X328150Y335339D03*
Y330220D03*
Y337898D03*
Y332780D03*
Y327661D03*
Y325102D03*
Y322543D03*
Y340457D03*
X403550Y358543D03*
Y361102D03*
Y363661D03*
Y366220D03*
Y368780D03*
Y371339D03*
Y373898D03*
Y376457D03*
X416950Y306643D03*
Y309202D03*
Y311761D03*
Y314320D03*
Y316880D03*
Y319439D03*
Y321998D03*
Y324557D03*
X427450Y371339D03*
Y368780D03*
Y366220D03*
Y363661D03*
Y361102D03*
Y358543D03*
Y376457D03*
Y373898D03*
X440850Y319439D03*
Y316880D03*
Y314320D03*
Y311761D03*
Y309202D03*
Y306643D03*
Y324557D03*
Y321998D03*
X488550Y74043D03*
Y76602D03*
Y79161D03*
Y81720D03*
Y84280D03*
Y86839D03*
Y89398D03*
Y91957D03*
X512450Y76602D03*
Y74043D03*
Y91957D03*
Y89398D03*
Y86839D03*
Y84280D03*
Y81720D03*
Y79161D03*
G54D28*
X74593Y209100D03*
X86207D03*
G54D37*
X89848Y263200D03*
X95248D03*
X158800Y377600D03*
X153400D03*
X341100Y420200D03*
X346500D03*
X361800Y147000D03*
X367200D03*
X362800Y220500D03*
X368200D03*
X370800Y309900D03*
X365400D03*
X459800Y386000D03*
X465200D03*
X523700Y172500D03*
X518300D03*
X531400Y390200D03*
X547900Y356900D03*
X536800Y390200D03*
X553300Y356900D03*
X603300Y232400D03*
X608700D03*
G54D91*
X478656Y367205D03*
Y375079D03*
Y382953D03*
Y390827D03*
X491549Y367205D03*
Y375079D03*
Y382953D03*
Y390827D03*
G54D19*
X20550Y95650D03*
Y209650D03*
G54D46*
X162033Y299531D03*
Y301500D03*
Y303469D03*
X173967D03*
Y301500D03*
Y299531D03*
X504833Y268731D03*
X516767D03*
X504833Y270700D03*
Y272669D03*
X516767D03*
Y270700D03*
X556533Y69869D03*
X568467D03*
X556533Y67900D03*
Y65931D03*
X568467Y67900D03*
Y65931D03*
G54D73*
X363673Y232557D03*
Y234643D03*
Y241243D03*
Y239157D03*
X398200Y310043D03*
Y307957D03*
X551000Y232957D03*
Y235043D03*
X564000Y232957D03*
Y235043D03*
X569500Y233457D03*
Y235543D03*
G54D82*
X410463Y389690D03*
Y408710D03*
X418337Y389690D03*
X416369D03*
X414400D03*
X412431D03*
Y408710D03*
X414400D03*
X416369D03*
X418337D03*
G54D55*
X158104Y395616D03*
Y399553D03*
Y393647D03*
Y397584D03*
X341796Y402184D03*
Y398247D03*
Y404153D03*
Y400216D03*
G54D38*
X89400Y320136D03*
Y337853D03*
Y335884D03*
Y333916D03*
Y331947D03*
Y329979D03*
Y328010D03*
Y326042D03*
Y324073D03*
Y322105D03*
Y349664D03*
Y347695D03*
Y345727D03*
Y343758D03*
Y341790D03*
Y339821D03*
X135200Y320136D03*
Y322105D03*
Y324073D03*
Y326042D03*
Y328010D03*
Y329979D03*
Y331947D03*
Y333916D03*
Y335884D03*
Y337853D03*
Y345727D03*
Y347695D03*
Y349664D03*
Y339821D03*
Y341790D03*
Y343758D03*
G54D74*
X388000Y75217D03*
Y89783D03*
X398000Y75217D03*
X408000D03*
Y89783D03*
X398000D03*
G54D29*
X80400Y215104D03*
G54D83*
X408494Y389540D03*
Y408860D03*
X420306Y389540D03*
Y408860D03*
G54D47*
X162033Y305888D03*
X504833Y275088D03*
X556533Y72288D03*
G54D65*
X305000Y374787D03*
Y398213D03*
G54D92*
X529750Y147000D03*
X519250D03*
X529750Y134500D03*
X519250D03*
X529750Y159500D03*
X519250D03*
G54D56*
X183661Y13781D03*
X179724D03*
X199409D03*
X195472D03*
X187598D03*
X191535D03*
X219094D03*
X207283D03*
X215157D03*
X211220D03*
X203346D03*
X230905D03*
X234842D03*
X250590D03*
X238779D03*
X242716D03*
X254527D03*
X246653D03*
X258464D03*
X262401D03*
X270275D03*
X266338D03*
X289960D03*
X274212D03*
X278149D03*
X286023D03*
X282086D03*
X301771D03*
X293897D03*
X297834D03*
X309645D03*
G54D39*
X97536Y312000D03*
Y357800D03*
X113284Y312000D03*
X111316D03*
X109347D03*
X107379D03*
X105410D03*
X103442D03*
X101473D03*
X99505D03*
Y357800D03*
X101473D03*
X103442D03*
X105410D03*
X107379D03*
X109347D03*
X111316D03*
X113284D03*
X127064Y312000D03*
X125095D03*
X123127D03*
X121158D03*
X119190D03*
X117221D03*
X115253D03*
Y357800D03*
X117221D03*
X119190D03*
X121158D03*
X123127D03*
X125095D03*
X127064D03*
G54D84*
X404740Y393294D03*
Y405106D03*
X424060D03*
Y393294D03*
G54D48*
X159669Y317000D03*
Y327000D03*
X168331Y317000D03*
Y327000D03*
G54D93*
X529108Y330600D03*
X555092D03*
G54D75*
X389161Y141035D03*
Y137098D03*
X393098Y141035D03*
Y137098D03*
Y133161D03*
X389161D03*
X393098Y144973D03*
X389161D03*
X393098Y156784D03*
Y148910D03*
X389161Y156784D03*
Y148910D03*
X393098Y152847D03*
X389161D03*
X393098Y160721D03*
X389161D03*
X393098Y164658D03*
Y172532D03*
X389161Y164658D03*
Y176469D03*
X393098D03*
X389161Y172532D03*
X393098Y180406D03*
X389161D03*
X393098Y168595D03*
X389161D03*
X393098Y184343D03*
X389161Y196154D03*
Y188280D03*
Y192217D03*
X393098Y188280D03*
Y192217D03*
Y196154D03*
X389161Y184343D03*
Y215839D03*
X393098Y204028D03*
Y211902D03*
X389161D03*
X393098Y215839D03*
X389161Y200091D03*
Y204028D03*
X393098Y207965D03*
X389161D03*
X393098Y200091D03*
X408847Y137098D03*
X397035Y133161D03*
Y144973D03*
X404910D03*
X400973D03*
Y141035D03*
X397035D03*
X408847D03*
X404910D03*
X408847Y133161D03*
X404910Y137098D03*
X400973D03*
X404910Y133161D03*
X400973D03*
X397035Y137098D03*
X408847Y144973D03*
X397035Y160721D03*
X408847Y156784D03*
X404910Y160721D03*
X400973Y152847D03*
X408847Y148910D03*
X404910Y156784D03*
Y148910D03*
X400973Y160721D03*
X397035Y152847D03*
X408847Y160721D03*
Y152847D03*
X404910D03*
X400973Y156784D03*
Y148910D03*
X397035Y156784D03*
Y148910D03*
X408847Y176469D03*
X404910D03*
X408847Y164658D03*
X400973Y168595D03*
X408847Y172532D03*
X404910Y164658D03*
Y172532D03*
X400973Y180406D03*
Y176469D03*
X397035D03*
Y168595D03*
Y180406D03*
X404910D03*
X408847D03*
Y168595D03*
X404910D03*
X400973Y164658D03*
Y172532D03*
X397035Y164658D03*
Y172532D03*
X404910Y188280D03*
X408847Y196154D03*
X397035Y192217D03*
X400973Y184343D03*
Y188280D03*
X404910Y192217D03*
X400973D03*
X404910Y184343D03*
X397035D03*
Y188280D03*
X408847Y192217D03*
X404910Y196154D03*
X408847Y184343D03*
X400973Y196154D03*
X397035D03*
X408847Y188280D03*
Y215839D03*
X400973Y200091D03*
X397035Y211902D03*
X404910Y207965D03*
Y211902D03*
X400973D03*
X404910Y215839D03*
X400973D03*
X397035D03*
X400973Y207965D03*
X397035D03*
X408847Y204028D03*
Y207965D03*
Y200091D03*
X404910D03*
Y204028D03*
X400973D03*
X397035Y200091D03*
Y204028D03*
X408847Y211902D03*
X420658Y141035D03*
X428532Y137098D03*
X416721Y133161D03*
X424595Y137098D03*
X420658D03*
X416721D03*
X412784D03*
X424595Y133161D03*
X420658D03*
X412784D03*
X428532Y144973D03*
Y133161D03*
Y141035D03*
X424595D03*
Y144973D03*
X420658D03*
X416721D03*
X412784D03*
X416721Y141035D03*
X412784D03*
X416721Y152847D03*
X428532Y156784D03*
X424595Y160721D03*
X420658Y156784D03*
X416721Y160721D03*
X428532D03*
X424595Y156784D03*
Y148910D03*
X420658Y160721D03*
X416721Y156784D03*
X412784Y160721D03*
Y156784D03*
Y152847D03*
Y148910D03*
X428532D03*
X424595Y152847D03*
X420658D03*
Y148910D03*
X416721D03*
X428532Y152847D03*
X420658Y180406D03*
Y164658D03*
X416721Y168595D03*
X428532Y172532D03*
X420658D03*
X424595Y176469D03*
X416721D03*
X424595Y168595D03*
Y172532D03*
X420658Y176469D03*
Y168595D03*
X416721Y164658D03*
Y172532D03*
X412784Y164658D03*
Y176469D03*
Y168595D03*
X424595Y164658D03*
X428532Y180406D03*
X416721D03*
X412784D03*
X424595D03*
X428532Y164658D03*
Y168595D03*
X412784Y172532D03*
X428532Y176469D03*
Y196154D03*
X416721Y192217D03*
X424595Y188280D03*
X412784Y184343D03*
X416721Y196154D03*
X420658Y188280D03*
X416721D03*
X412784Y196154D03*
X420658Y184343D03*
X416721D03*
X412784Y188280D03*
Y192217D03*
X428532D03*
X424595D03*
X428532Y184343D03*
Y188280D03*
X424595Y196154D03*
X420658D03*
X424595Y184343D03*
X420658Y192217D03*
X424595Y207965D03*
X412784Y204028D03*
X428532Y215839D03*
X420658Y200091D03*
X416721Y211902D03*
X424595D03*
Y215839D03*
X416721Y207965D03*
X412784D03*
X420658Y215839D03*
X416721D03*
Y200091D03*
X412784D03*
Y211902D03*
Y215839D03*
X428532Y200091D03*
Y204028D03*
Y207965D03*
X424595Y200091D03*
Y204028D03*
X420658D03*
X416721D03*
X420658Y207965D03*
Y211902D03*
X428532D03*
X436406Y133161D03*
X432469Y144973D03*
X440343Y141035D03*
X444280D03*
Y137098D03*
X440343D03*
X436406D03*
X440343Y144973D03*
X444280Y133161D03*
X440343D03*
X436406Y144973D03*
Y141035D03*
X432469D03*
Y137098D03*
Y133161D03*
X444280Y144973D03*
Y148910D03*
X436406Y156784D03*
X432469Y160721D03*
X444280Y156784D03*
X440343Y160721D03*
X444280D03*
X440343Y156784D03*
X436406Y160721D03*
Y152847D03*
X432469Y156784D03*
X440343Y152847D03*
X436406Y148910D03*
X432469Y152847D03*
Y148910D03*
X440343D03*
X444280Y152847D03*
X440343Y168595D03*
X444280Y164658D03*
X436406Y172532D03*
X444280D03*
X440343Y176469D03*
X432469D03*
X444280D03*
Y168595D03*
X440343Y164658D03*
Y180406D03*
Y172532D03*
X432469D03*
Y180406D03*
X436406D03*
X432469Y168595D03*
Y164658D03*
X444280Y180406D03*
X436406Y176469D03*
Y168595D03*
Y164658D03*
X444280Y188280D03*
X432469Y184343D03*
X436406Y192217D03*
X432469Y188280D03*
Y192217D03*
Y196154D03*
X440343Y192217D03*
X444280Y196154D03*
X436406Y184343D03*
X440343Y188280D03*
X444280Y192217D03*
X436406Y196154D03*
X440343D03*
Y184343D03*
X444280D03*
X436406Y188280D03*
Y211902D03*
X440343Y200091D03*
X444280Y207965D03*
X432469Y204028D03*
X436406Y207965D03*
X432469D03*
X436406Y200091D03*
Y204028D03*
X432469Y200091D03*
X436406Y215839D03*
X432469D03*
Y211902D03*
X440343Y204028D03*
X444280D03*
X440343Y211902D03*
X444280D03*
Y200091D03*
X440343Y215839D03*
X444280D03*
X440343Y207965D03*
X460028Y141035D03*
X448217Y137098D03*
X456091Y133161D03*
X452154Y144973D03*
X463965Y141035D03*
X452154D03*
X456091D03*
X460028Y133161D03*
X463965D03*
X460028Y137098D03*
X463965D03*
X452154D03*
X456091D03*
X448217Y133161D03*
X452154D03*
X448217Y144973D03*
X456091D03*
X460028D03*
X463965D03*
X448217Y141035D03*
X456091Y152847D03*
X448217Y160721D03*
X463965Y148910D03*
X460028Y160721D03*
X448217Y156784D03*
X463965Y160721D03*
Y156784D03*
X456091Y160721D03*
Y156784D03*
X460028D03*
X463965Y152847D03*
X448217D03*
X452154D03*
X456091Y148910D03*
X460028Y152847D03*
Y148910D03*
X448217D03*
X452154D03*
Y156784D03*
Y160721D03*
X463965Y168595D03*
X460028Y180406D03*
X448217Y176469D03*
Y168595D03*
X456091Y172532D03*
X448217Y164658D03*
Y172532D03*
X460028Y164658D03*
X463965D03*
X456091D03*
X463965Y180406D03*
X456091D03*
X460028Y172532D03*
Y176469D03*
X463965Y172532D03*
Y176469D03*
X456091Y168595D03*
X460028D03*
X448217Y180406D03*
X452154D03*
X456091Y176469D03*
X452154Y164658D03*
Y168595D03*
Y172532D03*
Y176469D03*
X456091Y192217D03*
X463965Y188280D03*
X452154Y184343D03*
X448217Y196154D03*
X460028Y184343D03*
X463965D03*
Y192217D03*
X452154Y196154D03*
X448217Y192217D03*
X452154D03*
X456091Y196154D03*
X460028Y188280D03*
Y196154D03*
Y192217D03*
X448217Y184343D03*
Y188280D03*
X452154D03*
X456091D03*
Y184343D03*
X463965Y196154D03*
Y207965D03*
X452154Y204028D03*
X448217Y215839D03*
X460028Y200091D03*
X456091Y211902D03*
X463965D03*
Y215839D03*
X460028Y211902D03*
Y215839D03*
X448217Y204028D03*
Y207965D03*
Y211902D03*
X452154D03*
Y215839D03*
X456091D03*
X448217Y200091D03*
X452154D03*
X456091D03*
Y204028D03*
X463965Y200091D03*
Y204028D03*
X460028D03*
Y207965D03*
X452154D03*
X456091D03*
X471839Y144973D03*
X467902Y137098D03*
Y141035D03*
X471839D03*
Y137098D03*
X467902Y133161D03*
X471839D03*
X467902Y144973D03*
Y156784D03*
Y160721D03*
X471839D03*
Y156784D03*
Y152847D03*
X467902D03*
Y148910D03*
X471839D03*
X467902Y176469D03*
X471839Y164658D03*
X467902Y168595D03*
Y172532D03*
Y164658D03*
X471839Y168595D03*
Y172532D03*
Y176469D03*
X467902Y180406D03*
X471839D03*
Y184343D03*
X467902Y196154D03*
Y184343D03*
Y188280D03*
X471839D03*
Y192217D03*
Y196154D03*
X467902Y192217D03*
X471839Y204028D03*
X467902Y215839D03*
Y207965D03*
Y211902D03*
Y200091D03*
X471839D03*
X467902Y204028D03*
X471839Y207965D03*
Y211902D03*
Y215839D03*
G54D57*
X173967Y297112D03*
X516767Y266312D03*
X568467Y63512D03*
G54D66*
X323744Y286500D03*
Y276500D03*
X344256Y286500D03*
Y276500D03*
X550544Y262100D03*
Y282100D03*
Y272100D03*
Y292100D03*
Y302100D03*
X571056Y262100D03*
Y282100D03*
Y272100D03*
Y302100D03*
Y292100D03*
X601844Y261500D03*
Y281500D03*
Y271500D03*
Y291500D03*
Y301500D03*
X622356Y261500D03*
Y281500D03*
Y271500D03*
Y301500D03*
Y291500D03*
G54D49*
X167800Y377600D03*
X164800Y415100D03*
X182200Y310500D03*
X184800Y326000D03*
X178200D03*
X174400Y377600D03*
X171400Y415100D03*
X188800Y310500D03*
X325500Y420200D03*
X328500Y382700D03*
X335100D03*
X332100Y420200D03*
X373200Y106000D03*
X379800D03*
X413400Y285500D03*
X420000D03*
X413400Y293600D03*
X420000D03*
X458800Y392700D03*
X465400D03*
X493300Y126400D03*
X499900D03*
X516200Y252100D03*
X508000Y253400D03*
X501400D03*
X527300Y124000D03*
X520700D03*
X522800Y252100D03*
X529800Y382700D03*
X548400Y86300D03*
X536400Y382700D03*
X563200Y85900D03*
X555000Y86300D03*
X565700Y161000D03*
X569800Y85900D03*
X572300Y161000D03*
G54D76*
X389231Y288533D03*
Y300467D03*
X391200Y288533D03*
X393169D03*
X391200Y300467D03*
X393169D03*
X596047Y214382D03*
X598016D03*
X599984D03*
X601953D03*
Y204418D03*
X599984D03*
X598016D03*
X596047D03*
G54D85*
X404890Y395263D03*
Y397231D03*
Y399200D03*
Y401169D03*
Y403137D03*
X423910D03*
Y401169D03*
Y399200D03*
Y397231D03*
Y395263D03*
G54D67*
X338016Y222296D03*
X339984D03*
X336047D03*
X339984Y240504D03*
X336047D03*
X338016D03*
X341953Y222296D03*
Y240504D03*
G54D58*
X173967Y305888D03*
X516767Y275088D03*
X568467Y72288D03*
G54D94*
X528300Y415049D03*
Y420953D03*
X543504Y407875D03*
Y421654D03*
Y413779D03*
Y427558D03*
X567126Y407875D03*
X555315D03*
Y421654D03*
X567126Y413779D03*
X555315D03*
X567126Y421654D03*
X555315Y427558D03*
X567126D03*
X578937Y407875D03*
Y413779D03*
Y421654D03*
Y427558D03*
X590748Y407875D03*
X602559D03*
Y421654D03*
X590748Y413779D03*
X602559D03*
Y427558D03*
X614370Y407875D03*
Y421654D03*
Y413779D03*
Y427558D03*
G54D95*
X552087Y209988D03*
Y212154D03*
Y214319D03*
X562913D03*
Y212154D03*
Y209988D03*
G54D86*
X429225Y282679D03*
Y284647D03*
Y286616D03*
Y288584D03*
Y290553D03*
Y292521D03*
X441975Y284647D03*
Y292521D03*
Y290553D03*
Y288584D03*
Y286616D03*
G54D77*
X386812Y288533D03*
G54D68*
X332848Y230416D03*
Y226479D03*
Y228447D03*
Y224510D03*
Y222542D03*
Y232384D03*
Y236321D03*
Y238290D03*
Y240258D03*
Y234353D03*
X345152Y230416D03*
Y228447D03*
Y226479D03*
Y224510D03*
Y222542D03*
Y232384D03*
Y234353D03*
Y236321D03*
Y238290D03*
Y240258D03*
G54D59*
X184387Y397600D03*
X207813D03*
G54D87*
X431400Y90634D03*
X441400D03*
X436400D03*
X431400Y82366D03*
X436400D03*
X441400D03*
G54D96*
X552087Y216878D03*
X562913D03*
G54D69*
X350595Y189187D03*
X358207Y192336D03*
Y193911D03*
Y189187D03*
Y190762D03*
X350595Y193911D03*
Y190762D03*
Y192336D03*
G54D78*
X386812Y300467D03*
G54D97*
X551004Y219240D03*
X563996D03*
G54D88*
X441975Y282429D03*
G54D79*
X395588Y300467D03*
G54D89*
X447200Y353150D03*
X439800D03*
X443500Y361850D03*
G54D98*
X547929Y365826D03*
Y367794D03*
Y369763D03*
Y371731D03*
Y373700D03*
Y375669D03*
Y377637D03*
Y379606D03*
Y381574D03*
X559271Y371731D03*
Y369763D03*
Y367794D03*
Y365826D03*
Y381574D03*
Y379606D03*
Y377637D03*
Y375669D03*
Y373700D03*
G54D99*
X559700Y173072D03*
Y194529D03*
M02*
